G04 ================== begin FILE IDENTIFICATION RECORD ==================*
G04 Layout Name:  12433-1M.brd*
G04 Film Name:    12433-1M_X_Y*
G04 File Format:  Gerber RS274X*
G04 File Origin:  Cadence Allegro 16.2-S037*
G04 Origin Date:  Fri Dec 07 18:55:02 2012*
G04 *
G04 Layer:  BOARD GEOMETRY/PANEL_DRAWING*
G04 *
G04 Offset:    (0.00 0.00)*
G04 Mirror:    No*
G04 Mode:      Positive*
G04 Rotation:  0*
G04 FullContactRelief:  No*
G04 UndefLineWidth:     6.00*
G04 ================== end FILE IDENTIFICATION RECORD ====================*
%FSLAX35Y35*MOIN*%
%IR0*IPPOS*OFA0.00000B0.00000*MIA0B0*SFA1.00000B1.00000*%
%ADD10C,.006*%
G75*
%LPD*%
G75*
G54D10*
G01X-552193Y-84022D02*
Y2112671D01*
G01X2572413Y-84022D02*
X-552193D01*
G01X-533256Y-65085D02*
Y2093734D01*
G01X2553476Y-65085D02*
X-533256D01*
G01X-545092Y39447D02*
X-544381Y38311D01*
X-543529Y37554D01*
X-542535Y37175D01*
X-541399Y37554D01*
X-540547Y38311D01*
X-539694Y39447D01*
X-539410Y40962D01*
Y48537D01*
G01X-552193Y150797D02*
X-533256D01*
G01X-543955Y264419D02*
X-540547D01*
G01X-542251D02*
Y253057D01*
G01X-543955D02*
X-540547D01*
G01X-552193Y366679D02*
X-533256D01*
G01X-552193D02*
X-533256D01*
G01X-545234Y468749D02*
Y480111D01*
G01X-539268D02*
Y468749D01*
G01Y474430D02*
X-545234D01*
G01X-552193Y582561D02*
X-533256D01*
G01X-552193D02*
X-533256D01*
G01X-541399Y690312D02*
X-538558D01*
Y686903D01*
X-539410Y685767D01*
X-540405Y685010D01*
X-541825Y684631D01*
X-543245Y685010D01*
X-544239Y685767D01*
X-545092Y686903D01*
X-545660Y688229D01*
X-545944Y689744D01*
Y691069D01*
X-545660Y692205D01*
X-545092Y693531D01*
X-544239Y694667D01*
X-543387Y695425D01*
X-542251Y695993D01*
X-541257D01*
X-540121Y695614D01*
X-539268Y694857D01*
G01X-552193Y798443D02*
X-533256D01*
G01X-552193D02*
X-533256D01*
G01X-545328Y900703D02*
Y912065D01*
X-539930D01*
G01X-541919Y906573D02*
X-545328D01*
G01X-552193Y1014325D02*
X-533256D01*
G01X-552193D02*
X-533256D01*
G01X-552193D02*
X-533256D01*
G01X-539410Y1116774D02*
X-545092D01*
Y1128136D01*
X-539410D01*
G01X-541683Y1122644D02*
X-545092D01*
G01X-552193Y1230206D02*
X-533256D01*
G01X-552193D02*
X-533256D01*
G01X-545376Y1332466D02*
Y1343828D01*
X-542535D01*
X-541399Y1343260D01*
X-540547Y1342502D01*
X-539836Y1341366D01*
X-539268Y1340040D01*
X-539126Y1338147D01*
X-539268Y1336253D01*
X-539836Y1334928D01*
X-540547Y1333791D01*
X-541399Y1333034D01*
X-542535Y1332466D01*
X-545376D01*
G01X-552193Y1446088D02*
X-533256D01*
G01X-552193D02*
X-533256D01*
G01X-539126Y1558953D02*
X-539979Y1559521D01*
X-540973Y1559900D01*
X-542109D01*
X-543387Y1559332D01*
X-544381Y1558385D01*
X-545092Y1557249D01*
X-545660Y1555355D01*
X-545802Y1553651D01*
X-545518Y1551947D01*
X-545092Y1550810D01*
X-544239Y1549674D01*
X-543245Y1548917D01*
X-542251Y1548538D01*
X-541257D01*
X-540263Y1548917D01*
X-539410Y1549485D01*
X-538700Y1550242D01*
G01X-552193Y1661970D02*
X-533256D01*
G01X-552193D02*
X-533256D01*
G01X-541115Y1770290D02*
X-540547Y1770858D01*
X-540121Y1771804D01*
X-539836Y1773130D01*
X-540121Y1774266D01*
X-540689Y1775024D01*
X-541683Y1775592D01*
X-545518D01*
Y1764230D01*
X-540831D01*
X-539836Y1764987D01*
X-539268Y1766124D01*
X-538984Y1767449D01*
X-539268Y1768775D01*
X-540121Y1769911D01*
X-541115Y1770290D01*
X-545518D01*
G01X-552193Y1877852D02*
X-533256D01*
G01X-545802Y1980112D02*
X-542251Y1991474D01*
X-538700Y1980112D01*
G01X-539979Y1984089D02*
X-544524D01*
G01X-552193Y2112671D02*
X2572413D01*
G01X-533256Y2093734D02*
X2553476D01*
G01X-415373Y-80235D02*
Y-68873D01*
X-417077Y-71145D01*
G01Y-80235D02*
X-413669D01*
G01X-415373Y2097521D02*
Y2108883D01*
X-417077Y2106611D01*
G01Y2097521D02*
X-413669D01*
G01X-335560Y1966875D02*
X-334992Y1966244D01*
X-334329Y1965865D01*
X-333477Y1965739D01*
X-332624Y1965991D01*
X-331962Y1966496D01*
X-331488Y1967380D01*
X-331393Y1968390D01*
X-331583Y1969400D01*
X-332056Y1970032D01*
X-332719Y1970536D01*
X-333382Y1970663D01*
X-334045Y1970536D01*
X-334897Y1970032D01*
X-334613Y1973314D01*
X-332056D01*
G01X-325902D02*
X-326659Y1973062D01*
X-327227Y1972430D01*
X-327606Y1971673D01*
X-327890Y1970663D01*
X-327985Y1969526D01*
X-327890Y1968390D01*
X-327606Y1967380D01*
X-327227Y1966623D01*
X-326659Y1965991D01*
X-325902Y1965739D01*
X-325144Y1965991D01*
X-324576Y1966623D01*
X-324197Y1967380D01*
X-323913Y1968390D01*
X-323818Y1969526D01*
X-323913Y1970663D01*
X-324197Y1971673D01*
X-324576Y1972430D01*
X-325144Y1973062D01*
X-325902Y1973314D01*
G01X-318327D02*
X-319084Y1973062D01*
X-319652Y1972430D01*
X-320031Y1971673D01*
X-320315Y1970663D01*
X-320410Y1969526D01*
X-320315Y1968390D01*
X-320031Y1967380D01*
X-319652Y1966623D01*
X-319084Y1965991D01*
X-318327Y1965739D01*
X-317569Y1965991D01*
X-317001Y1966623D01*
X-316622Y1967380D01*
X-316338Y1968390D01*
X-316243Y1969526D01*
X-316338Y1970663D01*
X-316622Y1971673D01*
X-317001Y1972430D01*
X-317569Y1973062D01*
X-318327Y1973314D01*
G01X-310752Y1965487D02*
X-310941Y1965613D01*
Y1965865D01*
X-310752Y1965991D01*
X-310562Y1965865D01*
Y1965613D01*
X-310752Y1965487D01*
G01X-303177Y1973314D02*
X-303934Y1973062D01*
X-304502Y1972430D01*
X-304881Y1971673D01*
X-305165Y1970663D01*
X-305260Y1969526D01*
X-305165Y1968390D01*
X-304881Y1967380D01*
X-304502Y1966623D01*
X-303934Y1965991D01*
X-303177Y1965739D01*
X-302419Y1965991D01*
X-301851Y1966623D01*
X-301472Y1967380D01*
X-301188Y1968390D01*
X-301093Y1969526D01*
X-301188Y1970663D01*
X-301472Y1971673D01*
X-301851Y1972430D01*
X-302419Y1973062D01*
X-303177Y1973314D01*
G01X-295602D02*
X-296359Y1973062D01*
X-296927Y1972430D01*
X-297306Y1971673D01*
X-297590Y1970663D01*
X-297685Y1969526D01*
X-297590Y1968390D01*
X-297306Y1967380D01*
X-296927Y1966623D01*
X-296359Y1965991D01*
X-295602Y1965739D01*
X-294844Y1965991D01*
X-294276Y1966623D01*
X-293897Y1967380D01*
X-293613Y1968390D01*
X-293518Y1969526D01*
X-293613Y1970663D01*
X-293897Y1971673D01*
X-294276Y1972430D01*
X-294844Y1973062D01*
X-295602Y1973314D01*
G01X-307905Y-65085D02*
Y-84022D01*
G01X-319994Y-24242D02*
Y-17943D01*
X-322907Y-22457D01*
X-318971D01*
G01X-315664Y-22142D02*
X-313616D01*
G01X-309680Y-24242D02*
Y-20043D01*
G01Y-21093D02*
X-309365Y-20568D01*
X-308892Y-20148D01*
X-308262Y-20043D01*
X-307711Y-20148D01*
X-307239Y-20568D01*
X-307002Y-21303D01*
Y-24242D01*
G01X-303774Y-22982D02*
X-303302Y-23717D01*
X-302672Y-24137D01*
X-301963Y-24242D01*
X-301333Y-24137D01*
X-300703Y-23612D01*
X-300310Y-22982D01*
X-300231Y-22352D01*
X-300389Y-21618D01*
X-300940Y-21093D01*
X-301491Y-20882D01*
X-302200D01*
G01X-301491D02*
X-301018Y-20568D01*
X-300625Y-20043D01*
X-300467Y-19413D01*
X-300625Y-18783D01*
X-301018Y-18258D01*
X-301727Y-17943D01*
X-302436Y-18048D01*
X-303144Y-18468D01*
G01X-295743Y-24452D02*
X-295901Y-24347D01*
Y-24137D01*
X-295743Y-24032D01*
X-295585Y-24137D01*
Y-24347D01*
X-295743Y-24452D01*
G01X-291176Y-23297D02*
X-290704Y-23822D01*
X-290153Y-24137D01*
X-289444Y-24242D01*
X-288735Y-24032D01*
X-288184Y-23612D01*
X-287791Y-22877D01*
X-287712Y-22037D01*
X-287869Y-21198D01*
X-288263Y-20673D01*
X-288814Y-20253D01*
X-289365Y-20148D01*
X-289916Y-20253D01*
X-290625Y-20673D01*
X-290389Y-17943D01*
X-288263D01*
G01X-284877Y-23297D02*
X-284405Y-23822D01*
X-283854Y-24137D01*
X-283145Y-24242D01*
X-282436Y-24032D01*
X-281885Y-23612D01*
X-281492Y-22877D01*
X-281413Y-22037D01*
X-281570Y-21198D01*
X-281964Y-20673D01*
X-282515Y-20253D01*
X-283066Y-20148D01*
X-283617Y-20253D01*
X-284326Y-20673D01*
X-284090Y-17943D01*
X-281964D01*
G01X-321593Y-35221D02*
Y-31022D01*
G01Y-32072D02*
X-321278Y-31547D01*
X-320805Y-31127D01*
X-320175Y-31022D01*
X-319624Y-31127D01*
X-319152Y-31547D01*
X-318915Y-32282D01*
Y-35221D01*
G01X-315923D02*
X-313955Y-28922D01*
X-311987Y-35221D01*
G01X-312695Y-33016D02*
X-315215D01*
G01X-308522Y-33121D02*
X-306632D01*
G01X-307656Y-31757D02*
Y-34486D01*
G01X-301357Y-28922D02*
X-301987Y-29132D01*
X-302459Y-29657D01*
X-302774Y-30287D01*
X-303010Y-31127D01*
X-303089Y-32072D01*
X-303010Y-33016D01*
X-302774Y-33856D01*
X-302459Y-34486D01*
X-301987Y-35011D01*
X-301357Y-35221D01*
X-300727Y-35011D01*
X-300255Y-34486D01*
X-299940Y-33856D01*
X-299704Y-33016D01*
X-299625Y-32072D01*
X-299704Y-31127D01*
X-299940Y-30287D01*
X-300255Y-29657D01*
X-300727Y-29132D01*
X-301357Y-28922D01*
G01X-295058Y-35431D02*
X-295216Y-35326D01*
Y-35116D01*
X-295058Y-35011D01*
X-294900Y-35116D01*
Y-35326D01*
X-295058Y-35431D01*
G01X-288759Y-28922D02*
X-289389Y-29132D01*
X-289861Y-29657D01*
X-290176Y-30287D01*
X-290412Y-31127D01*
X-290491Y-32072D01*
X-290412Y-33016D01*
X-290176Y-33856D01*
X-289861Y-34486D01*
X-289389Y-35011D01*
X-288759Y-35221D01*
X-288129Y-35011D01*
X-287657Y-34486D01*
X-287342Y-33856D01*
X-287106Y-33016D01*
X-287027Y-32072D01*
X-287106Y-31127D01*
X-287342Y-30287D01*
X-287657Y-29657D01*
X-288129Y-29132D01*
X-288759Y-28922D01*
G01X-282618Y-35221D02*
X-282460Y-33856D01*
X-282224Y-32702D01*
X-281909Y-31652D01*
X-281515Y-30497D01*
X-280885Y-28922D01*
X-284035D01*
G01X-277893Y-34276D02*
X-277421Y-34801D01*
X-276870Y-35116D01*
X-276161Y-35221D01*
X-275452Y-35011D01*
X-274901Y-34591D01*
X-274508Y-33856D01*
X-274429Y-33016D01*
X-274586Y-32177D01*
X-274980Y-31652D01*
X-275531Y-31232D01*
X-276082Y-31127D01*
X-276633Y-31232D01*
X-277342Y-31652D01*
X-277106Y-28922D01*
X-274980D01*
G01X-301178Y-44501D02*
X-299130D01*
G01X-293855Y-40302D02*
X-294485Y-40512D01*
X-294957Y-41037D01*
X-295272Y-41667D01*
X-295508Y-42507D01*
X-295587Y-43452D01*
X-295508Y-44396D01*
X-295272Y-45236D01*
X-294957Y-45866D01*
X-294485Y-46391D01*
X-293855Y-46601D01*
X-293225Y-46391D01*
X-292753Y-45866D01*
X-292438Y-45236D01*
X-292202Y-44396D01*
X-292123Y-43452D01*
X-292202Y-42507D01*
X-292438Y-41667D01*
X-292753Y-41037D01*
X-293225Y-40512D01*
X-293855Y-40302D01*
G01X-283304Y-46601D02*
Y-40302D01*
X-281257Y-45551D01*
X-279210Y-40302D01*
Y-46601D01*
G01X-277005D02*
Y-40302D01*
X-274958Y-45551D01*
X-272911Y-40302D01*
Y-46601D01*
G01X-261811Y-19685D02*
X-281496D01*
G01X-317941Y3624D02*
X-318698Y3372D01*
X-319266Y2740D01*
X-319645Y1983D01*
X-319929Y973D01*
X-320024Y-164D01*
X-319929Y-1300D01*
X-319645Y-2310D01*
X-319266Y-3067D01*
X-318698Y-3699D01*
X-317941Y-3951D01*
X-317183Y-3699D01*
X-316615Y-3067D01*
X-316236Y-2310D01*
X-315952Y-1300D01*
X-315857Y-164D01*
X-315952Y973D01*
X-316236Y1983D01*
X-316615Y2740D01*
X-317183Y3372D01*
X-317941Y3624D01*
G01X-310366Y-4203D02*
X-310555Y-4077D01*
Y-3825D01*
X-310366Y-3699D01*
X-310176Y-3825D01*
Y-4077D01*
X-310366Y-4203D01*
G01X-302791Y3624D02*
X-303548Y3372D01*
X-304116Y2740D01*
X-304495Y1983D01*
X-304779Y973D01*
X-304874Y-164D01*
X-304779Y-1300D01*
X-304495Y-2310D01*
X-304116Y-3067D01*
X-303548Y-3699D01*
X-302791Y-3951D01*
X-302033Y-3699D01*
X-301465Y-3067D01*
X-301086Y-2310D01*
X-300802Y-1300D01*
X-300707Y-164D01*
X-300802Y973D01*
X-301086Y1983D01*
X-301465Y2740D01*
X-302033Y3372D01*
X-302791Y3624D01*
G01X-295216D02*
X-295973Y3372D01*
X-296541Y2740D01*
X-296920Y1983D01*
X-297204Y973D01*
X-297299Y-164D01*
X-297204Y-1300D01*
X-296920Y-2310D01*
X-296541Y-3067D01*
X-295973Y-3699D01*
X-295216Y-3951D01*
X-294458Y-3699D01*
X-293890Y-3067D01*
X-293511Y-2310D01*
X-293227Y-1300D01*
X-293132Y-164D01*
X-293227Y973D01*
X-293511Y1983D01*
X-293890Y2740D01*
X-294458Y3372D01*
X-295216Y3624D01*
G01X-284993Y-14D02*
X-300741D01*
G01X-269245Y0D02*
X-284993Y-14D01*
G01X-286094Y1969676D02*
X-301842D01*
G01X-270346Y1968504D02*
X-286094Y1969676D01*
G01X-307905Y2112671D02*
Y2093734D01*
G01X-222441Y19685D02*
X-261811Y-19685D01*
G01X-174370Y0D02*
X-269245D01*
G01X-215453Y19685D02*
G03I-6988J0D01*
G01D02*
G03I-6988J0D01*
G01D02*
G03I-6988J0D01*
G01X-242126Y15000D02*
G03X-227126Y0I15000J0D01*
G01X-242126Y1953504D02*
Y15000D01*
G01X-84646Y0D02*
X-227126D01*
G01X-228941Y8085D02*
X-234041Y13185D01*
G01X-222441Y19685D02*
X-228941Y8085D01*
G01X-234041Y13185D02*
X-222441Y19685D01*
G01X-186098Y1968504D02*
X-270346D01*
G01X-242126Y1953750D02*
Y2008799D01*
G01X-215453Y1948819D02*
G03I-6988J0D01*
G01D02*
G03I-6988J0D01*
G01D02*
G03I-6988J0D01*
G01X-227126Y1968504D02*
G03X-242126Y1953504I0J-15000D01*
G01X-84638Y1968504D02*
X-227126D01*
G01X-245764Y2011993D02*
X-245512Y2011236D01*
X-244880Y2010668D01*
X-244123Y2010289D01*
X-243113Y2010005D01*
X-241976Y2009910D01*
X-240840Y2010005D01*
X-239830Y2010289D01*
X-239073Y2010668D01*
X-238441Y2011236D01*
X-238189Y2011993D01*
X-238441Y2012751D01*
X-239073Y2013319D01*
X-239830Y2013698D01*
X-240840Y2013982D01*
X-241976Y2014077D01*
X-243113Y2013982D01*
X-244123Y2013698D01*
X-244880Y2013319D01*
X-245512Y2012751D01*
X-245764Y2011993D01*
G01X-237937Y2019568D02*
X-238063Y2019379D01*
X-238315D01*
X-238441Y2019568D01*
X-238315Y2019758D01*
X-238063D01*
X-237937Y2019568D01*
G01X-245764Y2027143D02*
X-245512Y2026386D01*
X-244880Y2025818D01*
X-244123Y2025439D01*
X-243113Y2025155D01*
X-241976Y2025060D01*
X-240840Y2025155D01*
X-239830Y2025439D01*
X-239073Y2025818D01*
X-238441Y2026386D01*
X-238189Y2027143D01*
X-238441Y2027901D01*
X-239073Y2028469D01*
X-239830Y2028848D01*
X-240840Y2029132D01*
X-241976Y2029227D01*
X-243113Y2029132D01*
X-244123Y2028848D01*
X-244880Y2028469D01*
X-245512Y2027901D01*
X-245764Y2027143D01*
G01Y2034718D02*
X-245512Y2033961D01*
X-244880Y2033393D01*
X-244123Y2033014D01*
X-243113Y2032730D01*
X-241976Y2032635D01*
X-240840Y2032730D01*
X-239830Y2033014D01*
X-239073Y2033393D01*
X-238441Y2033961D01*
X-238189Y2034718D01*
X-238441Y2035476D01*
X-239073Y2036044D01*
X-239830Y2036423D01*
X-240840Y2036707D01*
X-241976Y2036802D01*
X-243113Y2036707D01*
X-244123Y2036423D01*
X-244880Y2036044D01*
X-245512Y2035476D01*
X-245764Y2034718D01*
G01X-200296Y-70767D02*
X-199443Y-69631D01*
X-198449Y-69062D01*
X-197313Y-68873D01*
X-195893Y-69252D01*
X-194898Y-70199D01*
X-194614Y-71335D01*
X-194756Y-72471D01*
X-195325Y-73418D01*
X-198165Y-75311D01*
X-199443Y-76637D01*
X-200296Y-78531D01*
X-200580Y-80235D01*
X-194614D01*
G01X-222441Y39370D02*
G03X-214567Y31496I7874J0D01*
G01X-206693D02*
X-214567D01*
G01X-206693D02*
X-214567D01*
G01X-84646Y0D02*
X-199567D01*
G01X-175984Y31496D02*
X-84646D01*
G01X-206693D02*
G03Y39370I0J3937D01*
G01X-175984D02*
G03Y31496I0J-3937D01*
G01D02*
X-84646D01*
G01X-206693D02*
G03Y39370I0J3937D01*
G01X-175984D02*
G03Y31496I0J-3937D01*
G01X-189139Y28007D02*
X-173139D01*
G01X-189139Y12007D02*
X-173139D01*
G01X-189139Y28007D02*
Y12007D01*
G01X-183639Y17507D02*
X-178639D01*
G01Y22507D02*
X-183639D01*
G01Y17507D02*
Y22507D01*
G01X-178639D02*
Y17507D01*
G01X-181139D02*
Y22507D01*
G01X-183639Y20007D02*
X-178639D01*
G01X-222441Y169326D02*
Y39370D01*
G01X-214567Y43307D02*
G03X-210630Y39370I3937J0D01*
G01X-214567Y43307D02*
G03X-210630Y39370I3937J0D01*
G01X-80709D02*
X-210630D01*
G01X-80709D02*
X-210630D01*
G01X-214567Y43307D02*
Y1925197D01*
G01Y43307D02*
Y1925197D01*
G01Y149606D02*
Y43307D01*
G01Y149606D02*
Y43272D01*
G01Y169326D02*
G03X-222441I-3937J0D01*
G01X-214567D02*
G03X-222441I-3937J0D01*
G01X-214567Y1807087D02*
Y161417D01*
G01Y1807087D02*
Y161417D01*
G01X-222441Y436255D02*
Y200034D01*
G01D02*
G03X-214567I3937J0D01*
G01X-222441D02*
G03X-214567I3937J0D01*
G01Y436255D02*
G03X-222441I-3937J0D01*
G01X-214567D02*
G03X-222441I-3937J0D01*
G01Y703184D02*
Y466963D01*
G01D02*
G03X-214567I3937J0D01*
G01X-222441D02*
G03X-214567I3937J0D01*
G01X-222441Y970901D02*
Y733892D01*
G01X-214567Y703184D02*
G03X-222441I-3937J0D01*
G01Y733892D02*
G03X-214567I3937J0D01*
G01Y703184D02*
G03X-222441I-3937J0D01*
G01Y733892D02*
G03X-214567I3937J0D01*
G01X-222441Y1234681D02*
Y997672D01*
G01X-214567Y970901D02*
G03X-222441I-3937J0D01*
G01Y997672D02*
G03X-214567I3937J0D01*
G01Y970901D02*
G03X-222441I-3937J0D01*
G01Y997672D02*
G03X-214567I3937J0D01*
G01X-222441Y1265389D02*
G03X-214567I3937J0D01*
G01Y1234681D02*
G03X-222441I-3937J0D01*
G01Y1265389D02*
G03X-214567I3937J0D01*
G01Y1234681D02*
G03X-222441I-3937J0D01*
G01Y1501610D02*
Y1265389D01*
G01X-214567Y1501610D02*
G03X-222441I-3937J0D01*
G01X-214567D02*
G03X-222441I-3937J0D01*
G01Y1768539D02*
Y1532318D01*
G01D02*
G03X-214567I3937J0D01*
G01X-222441D02*
G03X-214567I3937J0D01*
G01Y1768539D02*
G03X-222441I-3937J0D01*
G01X-214567D02*
G03X-222441I-3937J0D01*
G01Y1799247D02*
G03X-214567I3937J0D01*
G01X-222441D02*
G03X-214567I3937J0D01*
G01X-222441Y1929134D02*
Y1799247D01*
G01X-214567Y1818898D02*
Y1925231D01*
G01Y1818898D02*
Y1925231D01*
G01Y1915382D02*
Y1977555D01*
G01X-210630Y1929134D02*
G03X-214567Y1925197I0J-3937D01*
G01X-210630Y1929134D02*
G03X-214567Y1925197I0J-3937D01*
G01Y1977555D02*
X-212116Y1993304D01*
G01X-214567Y1937008D02*
G03X-222441Y1929134I0J-7874D01*
G01X-214567Y1937008D02*
X-206693D01*
G01X-214567D02*
X-206693D01*
G01X-172445Y1939256D02*
X-188445D01*
G01Y1955256D02*
Y1939256D01*
G01X-172445Y1955256D02*
X-188445D01*
G01X-177945Y1949756D02*
X-182945D01*
G01Y1944756D02*
X-177945D01*
G01Y1949756D02*
Y1944756D01*
G01X-182945D02*
Y1949756D01*
G01X-180445D02*
Y1944756D01*
G01X-177945Y1947256D02*
X-182945D01*
G01X-210630Y1929134D02*
X-80709D01*
G01X-210630D02*
X-80709D01*
G01X-175984Y1937008D02*
X-84638D01*
G01X-175984D02*
G03Y1929134I0J-3937D01*
G01X-206693D02*
G03Y1937008I0J3937D01*
G01X-175984D02*
X-84638D01*
G01X-175984D02*
G03Y1929134I0J-3937D01*
G01X-206693D02*
G03Y1937008I0J3937D01*
G01X-208179Y2012057D02*
X-209820Y2012246D01*
X-211209Y2012531D01*
X-212472Y2012909D01*
X-213860Y2013383D01*
X-215754Y2014140D01*
Y2010353D01*
G01X-207927Y2019821D02*
X-208053Y2019632D01*
X-208305D01*
X-208431Y2019821D01*
X-208305Y2020011D01*
X-208053D01*
X-207927Y2019821D01*
G01X-215754Y2027396D02*
X-215502Y2026639D01*
X-214870Y2026071D01*
X-214113Y2025692D01*
X-213103Y2025408D01*
X-211966Y2025313D01*
X-210830Y2025408D01*
X-209820Y2025692D01*
X-209063Y2026071D01*
X-208431Y2026639D01*
X-208179Y2027396D01*
X-208431Y2028154D01*
X-209063Y2028722D01*
X-209820Y2029101D01*
X-210830Y2029385D01*
X-211966Y2029480D01*
X-213103Y2029385D01*
X-214113Y2029101D01*
X-214870Y2028722D01*
X-215502Y2028154D01*
X-215754Y2027396D01*
G01Y2034971D02*
X-215502Y2034214D01*
X-214870Y2033646D01*
X-214113Y2033267D01*
X-213103Y2032983D01*
X-211966Y2032888D01*
X-210830Y2032983D01*
X-209820Y2033267D01*
X-209063Y2033646D01*
X-208431Y2034214D01*
X-208179Y2034971D01*
X-208431Y2035729D01*
X-209063Y2036297D01*
X-209820Y2036676D01*
X-210830Y2036960D01*
X-211966Y2037055D01*
X-213103Y2036960D01*
X-214113Y2036676D01*
X-214870Y2036297D01*
X-215502Y2035729D01*
X-215754Y2034971D01*
G01X-212116Y1993304D02*
Y2009052D01*
G01X-200296Y2106989D02*
X-199443Y2108125D01*
X-198449Y2108694D01*
X-197313Y2108883D01*
X-195893Y2108504D01*
X-194898Y2107557D01*
X-194614Y2106421D01*
X-194756Y2105285D01*
X-195325Y2104338D01*
X-198165Y2102445D01*
X-199443Y2101119D01*
X-200296Y2099225D01*
X-200580Y2097521D01*
X-194614D01*
G01X-173139Y12007D02*
Y28007D01*
G01X-140832Y934748D02*
Y984748D01*
G01X-126458Y934748D02*
X-155208D01*
G01X-172445Y1939256D02*
Y1955256D01*
G01X-88236Y-65085D02*
Y-84022D01*
G01X-76772Y3937D02*
G03X-72835Y0I3937J0D01*
G01X-76772Y35433D02*
G03X-80709Y39370I-3937J0D01*
G01X-76772Y35433D02*
G03X-80709Y39370I-3937J0D01*
G01X-76772Y3937D02*
G03X-72835Y0I3937J0D01*
G01X-76772Y3937D02*
Y35433D01*
G01Y3937D02*
Y35433D01*
G01Y3937D02*
G03X-72835Y0I3937J0D01*
G01X-84646Y7874D02*
Y0D01*
G01X-76772Y7874D02*
G03X-84646I-3937J0D01*
G01Y31496D02*
G03X-76772I3937J0D01*
G01Y3937D02*
G03X-72835Y0I3937J0D01*
G01X-84646Y7874D02*
Y0D01*
G01X-76772Y7874D02*
G03X-84646I-3937J0D01*
G01Y31496D02*
G03X-76772I3937J0D01*
G01X-76763Y1937008D02*
G03X-84638I-3937J0D01*
G01X-80709Y1929134D02*
G03X-76772Y1933071I0J3937D01*
G01X-80709Y1929134D02*
G03X-76772Y1933071I0J3937D01*
G01X-72835Y1968504D02*
G03X-76772Y1964567I0J-3937D01*
G01X-72835Y1968504D02*
G03X-76772Y1964567I0J-3937D01*
G01Y1933071D02*
Y1964567D01*
G01Y1933071D02*
Y1964567D01*
G01X-72835Y1968504D02*
G03X-76772Y1964567I0J-3937D01*
G01X-84638Y1960889D02*
Y1968504D01*
G01Y1960889D02*
G03X-76763I3938J0D01*
G01X-72835Y1968504D02*
G03X-76772Y1964567I0J-3937D01*
G01X-84638Y1960889D02*
Y1968504D01*
G01Y1960889D02*
G03X-76763I3938J0D01*
G01X-88236Y2112671D02*
Y2093734D01*
G01X-11811Y0D02*
X-72835D01*
G01X-11811D02*
X-72835D01*
G01D02*
X-11811D01*
G01X-72835D02*
X-11811D01*
G01X-23622Y48780D02*
X-22441Y49370D01*
G01X-23622Y58780D02*
X-22441Y59370D01*
G01X-23622Y68780D02*
X-22441Y69370D01*
G01X-23622Y78780D02*
X-22441Y79370D01*
G01Y86850D02*
Y89370D01*
G01Y76850D02*
Y79370D01*
G01Y66850D02*
Y69370D01*
G01Y56850D02*
Y59370D01*
G01Y46850D02*
Y49370D01*
G01X-23622Y87441D02*
Y88780D01*
G01Y77441D02*
Y78780D01*
G01Y67441D02*
Y68780D01*
G01Y57441D02*
Y58780D01*
G01Y47441D02*
Y48780D01*
G01Y87441D02*
X-22441Y86850D01*
G01X-23622Y77441D02*
X-22441Y76850D01*
G01X-23622Y67441D02*
X-22441Y66850D01*
G01X-23622Y57441D02*
X-22441Y56850D01*
G01X-23622Y47441D02*
X-22441Y46850D01*
G01X0Y86850D02*
X-22441D01*
G01X0Y79370D02*
X-22441D01*
G01X0Y76850D02*
X-22441D01*
G01X0Y69370D02*
X-22441D01*
G01X0Y66850D02*
X-22441D01*
G01X0Y59370D02*
X-22441D01*
G01X0Y56850D02*
X-22441D01*
G01X0Y49370D02*
X-22441D01*
G01X0Y46850D02*
X-22441D01*
G01X-23622Y88780D02*
X-22441Y89370D01*
G01X0D02*
X-22441D01*
G01X-23622Y482008D02*
X-22441Y482598D01*
G01X-23622Y492008D02*
X-22441Y492598D01*
G01Y490079D02*
Y492598D01*
G01Y480079D02*
Y482598D01*
G01X-23622Y490669D02*
Y492008D01*
G01Y480669D02*
Y482008D01*
G01Y490669D02*
X-22441Y490079D01*
G01X-23622Y480669D02*
X-22441Y480079D01*
G01X0Y492598D02*
X-22441D01*
G01X0Y490079D02*
X-22441D01*
G01X0Y482598D02*
X-22441D01*
G01X0Y480079D02*
X-22441D01*
G01X-23622Y502008D02*
X-22441Y502598D01*
G01X-23622Y512008D02*
X-22441Y512598D01*
G01X-23622Y522008D02*
X-22441Y522598D01*
G01Y520079D02*
Y522598D01*
G01Y510079D02*
Y512598D01*
G01Y500079D02*
Y502598D01*
G01X-23622Y520669D02*
Y522008D01*
G01Y510669D02*
Y512008D01*
G01Y500669D02*
Y502008D01*
G01Y520669D02*
X-22441Y520079D01*
G01X-23622Y510669D02*
X-22441Y510079D01*
G01X-23622Y500669D02*
X-22441Y500079D01*
G01X0Y522598D02*
X-22441D01*
G01X0Y520079D02*
X-22441D01*
G01X0Y512598D02*
X-22441D01*
G01X0Y510079D02*
X-22441D01*
G01X0Y502598D02*
X-22441D01*
G01X0Y500079D02*
X-22441D01*
G01X-23622Y741850D02*
X-22441Y742441D01*
G01X-23622Y751850D02*
X-22441Y752441D01*
G01Y749921D02*
Y752441D01*
G01Y739921D02*
Y742441D01*
G01X-23622Y750512D02*
Y751850D01*
G01Y740512D02*
Y741850D01*
G01X0Y749921D02*
X-22441D01*
G01X0Y742441D02*
X-22441D01*
G01X0Y739921D02*
X-22441D01*
G01X-23622Y750512D02*
X-22441Y749921D01*
G01X-23622Y740512D02*
X-22441Y739921D01*
G01X-23622Y761850D02*
X-22441Y762441D01*
G01X-23622Y771850D02*
X-22441Y772441D01*
G01X-23622Y781850D02*
X-22441Y782441D01*
G01Y779921D02*
Y782441D01*
G01Y769921D02*
Y772441D01*
G01Y759921D02*
Y762441D01*
G01X-23622Y780512D02*
Y781850D01*
G01Y770512D02*
Y771850D01*
G01Y760512D02*
Y761850D01*
G01Y780512D02*
X-22441Y779921D01*
G01X-23622Y770512D02*
X-22441Y769921D01*
G01X-23622Y760512D02*
X-22441Y759921D01*
G01X0Y782441D02*
X-22441D01*
G01X0Y779921D02*
X-22441D01*
G01X0Y772441D02*
X-22441D01*
G01X0Y769921D02*
X-22441D01*
G01X0Y762441D02*
X-22441D01*
G01X0Y759921D02*
X-22441D01*
G01X0Y752441D02*
X-22441D01*
G01X0Y1208583D02*
X-22441D01*
G01X0Y1206063D02*
X-22441D01*
G01X0Y1198583D02*
X-22441D01*
G01X0Y1196063D02*
X-22441D01*
G01X-23622Y1206654D02*
X-22441Y1206063D01*
G01X0Y1188583D02*
X-22441D01*
G01X0Y1186063D02*
X-22441D01*
G01X-23622Y1196654D02*
X-22441Y1196063D01*
G01X-23622Y1186654D02*
X-22441Y1186063D01*
G01Y1206063D02*
Y1208583D01*
G01Y1196063D02*
Y1198583D01*
G01Y1186063D02*
Y1188583D01*
G01X-23622Y1206654D02*
Y1207992D01*
G01Y1196654D02*
Y1197992D01*
G01Y1186654D02*
Y1187992D01*
G01D02*
X-22441Y1188583D01*
G01X-23622Y1197992D02*
X-22441Y1198583D01*
G01X-23622Y1207992D02*
X-22441Y1208583D01*
G01X0Y1228583D02*
X-22441D01*
G01X0Y1226063D02*
X-22441D01*
G01X0Y1218583D02*
X-22441D01*
G01X0Y1216063D02*
X-22441D01*
G01X-23622Y1226654D02*
X-22441Y1226063D01*
G01X-23622Y1216654D02*
X-22441Y1216063D01*
G01Y1226063D02*
Y1228583D01*
G01Y1216063D02*
Y1218583D01*
G01X-23622Y1226654D02*
Y1227992D01*
G01Y1216654D02*
Y1217992D01*
G01D02*
X-22441Y1218583D01*
G01X-23622Y1227992D02*
X-22441Y1228583D01*
G01X0Y1465906D02*
X-22441D01*
G01X0Y1458425D02*
X-22441D01*
G01X0Y1455906D02*
X-22441D01*
G01X0Y1448425D02*
X-22441D01*
G01X0Y1445906D02*
X-22441D01*
G01X-23622Y1466496D02*
X-22441Y1465906D01*
G01X-23622Y1456496D02*
X-22441Y1455906D01*
G01X-23622Y1446496D02*
X-22441Y1445906D01*
G01Y1465906D02*
Y1468425D01*
G01Y1455906D02*
Y1458425D01*
G01Y1445906D02*
Y1448425D01*
G01X-23622Y1466496D02*
Y1467835D01*
G01Y1456496D02*
Y1457835D01*
G01Y1446496D02*
Y1447835D01*
G01D02*
X-22441Y1448425D01*
G01X-23622Y1457835D02*
X-22441Y1458425D01*
G01X-23622Y1467835D02*
X-22441Y1468425D01*
G01X0Y1488425D02*
X-22441D01*
G01X0Y1485906D02*
X-22441D01*
G01X0Y1478425D02*
X-22441D01*
G01X0Y1475906D02*
X-22441D01*
G01X0Y1468425D02*
X-22441D01*
G01X-23622Y1486496D02*
X-22441Y1485906D01*
G01X-23622Y1476496D02*
X-22441Y1475906D01*
G01Y1485906D02*
Y1488425D01*
G01Y1475906D02*
Y1478425D01*
G01X-23622Y1486496D02*
Y1487835D01*
G01Y1476496D02*
Y1477835D01*
G01D02*
X-22441Y1478425D01*
G01X-23622Y1487835D02*
X-22441Y1488425D01*
G01X0Y1921654D02*
X-22441D01*
G01X0Y1919134D02*
X-22441D01*
G01X0Y1911654D02*
X-22441D01*
G01X0Y1909134D02*
X-22441D01*
G01X0Y1901654D02*
X-22441D01*
G01X0Y1899134D02*
X-22441D01*
G01X0Y1891654D02*
X-22441D01*
G01X0Y1889134D02*
X-22441D01*
G01X0Y1881654D02*
X-22441D01*
G01X0Y1879134D02*
X-22441D01*
G01X-23622Y1919724D02*
X-22441Y1919134D01*
G01X-23622Y1909724D02*
X-22441Y1909134D01*
G01X-23622Y1899724D02*
X-22441Y1899134D01*
G01X-23622Y1889724D02*
X-22441Y1889134D01*
G01X-23622Y1879724D02*
X-22441Y1879134D01*
G01Y1919134D02*
Y1921654D01*
G01Y1909134D02*
Y1911654D01*
G01Y1899134D02*
Y1901654D01*
G01Y1889134D02*
Y1891654D01*
G01Y1879134D02*
Y1881654D01*
G01X-23622Y1919724D02*
Y1921063D01*
G01Y1909724D02*
Y1911063D01*
G01Y1899724D02*
Y1901063D01*
G01Y1889724D02*
Y1891063D01*
G01Y1879724D02*
Y1881063D01*
G01D02*
X-22441Y1881654D01*
G01X-23622Y1891063D02*
X-22441Y1891654D01*
G01X-23622Y1901063D02*
X-22441Y1901654D01*
G01X-23622Y1911063D02*
X-22441Y1911654D01*
G01X-23622Y1921063D02*
X-22441Y1921654D01*
G01X-72835Y1968504D02*
X-11811D01*
G01X-72835D02*
X-11811D01*
G01D02*
X-72835D01*
G01X-11811D02*
X-72835D01*
G01X18947Y-77963D02*
X19799Y-79288D01*
X20936Y-80046D01*
X22214Y-80235D01*
X23350Y-80046D01*
X24487Y-79099D01*
X25197Y-77963D01*
X25339Y-76826D01*
X25055Y-75501D01*
X24060Y-74554D01*
X23066Y-74175D01*
X21788D01*
G01X23066D02*
X23918Y-73607D01*
X24629Y-72661D01*
X24913Y-71524D01*
X24629Y-70388D01*
X23918Y-69441D01*
X22640Y-68873D01*
X21362Y-69062D01*
X20084Y-69820D01*
G01X37008Y24803D02*
G03I-7087J0D01*
G01X0Y3937D02*
G03X3937Y0I3937J0D01*
G01X0Y3937D02*
Y43110D01*
G01X64961Y0D02*
X3937D01*
G01X0Y3937D02*
G03X3937Y0I3937J0D01*
G01X0Y3937D02*
G03X3937Y0I3937J0D01*
G01X0Y3937D02*
Y43110D01*
G01Y3937D02*
Y43110D01*
G01X64961Y0D02*
X3937D01*
G01X64961D02*
X3937D01*
G01X0Y1964567D02*
Y3937D01*
G01X-7874D02*
Y1964567D01*
G01X0Y11811D02*
G03X-7874I-3937J0D01*
G01X0Y1964567D02*
Y3937D01*
G01X-7874D02*
Y1964567D01*
G01X0Y11811D02*
G03X-7874I-3937J0D01*
G01X-11811Y0D02*
G03X-7874Y3937I0J3937D01*
G01X-11811Y0D02*
G03X-7874Y3937I0J3937D01*
G01X0D02*
G03X3937Y0I3937J0D01*
G01X0Y3937D02*
G03X3937Y0I3937J0D01*
G01X64961D02*
X3937D01*
G01X64961D02*
X3937D01*
G01X0Y3937D02*
G03X3937Y0I3937J0D01*
G01D02*
X64961D01*
G01X-11811D02*
G03X-7874Y3937I0J3937D01*
G01X0D02*
G03X3937Y0I3937J0D01*
G01D02*
X64961D01*
G01X-11811D02*
G03X-7874Y3937I0J3937D01*
G01X13907Y49370D02*
G03Y46850I1998J-1260D01*
G01Y59370D02*
G03Y56850I1998J-1260D01*
G01Y69370D02*
G03Y66850I1998J-1260D01*
G01Y79370D02*
G03Y76850I1998J-1260D01*
G01Y89370D02*
G03Y86850I1998J-1260D01*
G01X16575Y48780D02*
X17165Y49370D01*
G01X15236Y47441D02*
X14646Y46850D01*
G01X16575Y58780D02*
X17165Y59370D01*
G01X15236Y57441D02*
X14646Y56850D01*
G01X16575Y68780D02*
X17165Y69370D01*
G01X15236Y67441D02*
X14646Y66850D01*
G01X16575Y78780D02*
X17165Y79370D01*
G01X15236Y77441D02*
X14646Y76850D01*
G01X15236Y87441D02*
X14646Y86850D01*
G01X20512Y87057D02*
Y86811D01*
G01X19632Y87795D02*
Y87057D01*
G01X19381D02*
Y87836D01*
G01X18753D02*
Y87057D01*
G01X18543Y86811D02*
Y87795D01*
G01X17165Y49370D02*
Y46850D01*
G01Y59370D02*
Y56850D01*
G01Y69370D02*
Y66850D01*
G01Y79370D02*
Y76850D01*
G01Y89370D02*
Y86850D01*
G01X16575Y87441D02*
Y88780D01*
G01Y77441D02*
Y78780D01*
G01Y67441D02*
Y68780D01*
G01Y57441D02*
Y58780D01*
G01Y47441D02*
Y48780D01*
G01X15236Y87441D02*
Y88780D01*
G01Y77441D02*
Y78780D01*
G01Y67441D02*
Y68780D01*
G01Y57441D02*
Y58780D01*
G01Y47441D02*
Y48780D01*
G01X14646Y49370D02*
Y46850D01*
G01Y59370D02*
Y56850D01*
G01Y69370D02*
Y66850D01*
G01Y79370D02*
Y76850D01*
G01Y89370D02*
Y86850D01*
G01X13661Y49370D02*
Y46850D01*
G01Y59370D02*
Y56850D01*
G01Y69370D02*
Y66850D01*
G01Y79370D02*
Y76850D01*
G01Y89370D02*
Y86850D01*
G01X10000Y43110D02*
Y93110D01*
G01X8819D02*
Y43110D01*
G01X0D02*
Y93110D01*
G01Y43110D02*
Y93110D01*
G01Y43110D02*
Y93110D01*
G01X17165Y86850D02*
X16575Y87441D01*
G01X15236Y78780D02*
X14646Y79370D01*
G01X17165Y76850D02*
X16575Y77441D01*
G01X17165Y66850D02*
X16575Y67441D01*
G01X15236Y68780D02*
X14646Y69370D01*
G01X15236Y58780D02*
X14646Y59370D01*
G01X17165Y56850D02*
X16575Y57441D01*
G01X15236Y48780D02*
X14646Y49370D01*
G01X17165Y46850D02*
X16575Y47441D01*
G01X15236Y87441D02*
X16575D01*
G01X18753Y87057D02*
X19381D01*
G01X19632D02*
X20512D01*
G01X10000Y86850D02*
X8819D01*
G01X17165D02*
X10000D01*
G01X20512Y86811D02*
X18543D01*
G01X0Y84685D02*
X10000D01*
G01X0Y83898D02*
X10000D01*
G01Y82323D02*
X0D01*
G01X10000Y81535D02*
X0D01*
G01X10000Y79370D02*
X8819D01*
G01X17165D02*
X10000D01*
G01X16575Y78780D02*
X15236D01*
G01Y77441D02*
X16575D01*
G01X10000Y76850D02*
X8819D01*
G01X17165D02*
X10000D01*
G01X0Y74685D02*
X10000D01*
G01X0Y73898D02*
X10000D01*
G01Y72323D02*
X0D01*
G01X10000Y71535D02*
X0D01*
G01X10000Y69370D02*
X8819D01*
G01X17165D02*
X10000D01*
G01X16575Y68780D02*
X15236D01*
G01Y67441D02*
X16575D01*
G01X10000Y66850D02*
X8819D01*
G01X17165D02*
X10000D01*
G01X0Y64685D02*
X10000D01*
G01X0Y63898D02*
X10000D01*
G01Y62323D02*
X0D01*
G01X10000Y61535D02*
X0D01*
G01X10000Y59370D02*
X8819D01*
G01X17165D02*
X10000D01*
G01X16575Y58780D02*
X15236D01*
G01Y57441D02*
X16575D01*
G01X10000Y56850D02*
X8819D01*
G01X17165D02*
X10000D01*
G01X0Y54685D02*
X10000D01*
G01X0Y53898D02*
X10000D01*
G01Y52323D02*
X0D01*
G01X10000Y51535D02*
X0D01*
G01X10000Y49370D02*
X8819D01*
G01X17165D02*
X10000D01*
G01X16575Y48780D02*
X15236D01*
G01Y47441D02*
X16575D01*
G01X10000Y46850D02*
X8819D01*
G01X17165D02*
X10000D01*
G01X0Y44685D02*
X10000D01*
G01X0Y43898D02*
X10000D01*
G01X0Y43110D02*
X10000D01*
G01X0D02*
Y93110D01*
G01Y43110D02*
Y93110D01*
G01Y43110D02*
Y93110D01*
G01X-7874Y42520D02*
G03X0I3937J0D01*
G01X-7874D02*
G03X0I3937J0D01*
G01X37008Y111417D02*
G03I-7087J0D01*
G01X19004Y88082D02*
X18878Y88041D01*
G01Y88287D02*
X19004Y88328D01*
G01X18711Y88164D02*
X18878Y88287D01*
G01Y88041D02*
X18795Y87959D01*
G01X16575Y88780D02*
X17165Y89370D01*
G01X18585Y88000D02*
X18711Y88164D01*
G01X18795Y87959D02*
X18753Y87836D01*
G01X18543Y87795D02*
X18585Y88000D01*
G01X20512Y89149D02*
Y88903D01*
G01X18543D02*
Y89149D01*
G01X0Y93110D02*
Y214764D01*
G01X19590Y88000D02*
X19632Y87795D01*
G01X19381Y87836D02*
X19339Y87959D01*
G01X19465Y88164D02*
X19590Y88000D01*
G01X15236Y88780D02*
X14646Y89370D01*
G01X19339Y87959D02*
X19255Y88041D01*
G01X18878Y88903D02*
X19172Y88656D01*
G01X18836D02*
X18543Y88903D01*
G01X19297Y88287D02*
X19465Y88164D01*
G01X19172Y88328D02*
X19297Y88287D01*
G01X19255Y88041D02*
X19130Y88082D01*
G01X0Y93110D02*
X10000D01*
G01Y92323D02*
X0D01*
G01X10000Y91535D02*
X0D01*
G01X10000Y89370D02*
X8819D01*
G01X17165D02*
X10000D01*
G01X18543Y89149D02*
X20512D01*
G01Y88903D02*
X18878D01*
G01X16575Y88780D02*
X15236D01*
G01X19172Y88656D02*
X18836D01*
G01X19004Y88328D02*
X19172D01*
G01X19130Y88082D02*
X19004D01*
G01X0Y93110D02*
Y214764D01*
G01Y93110D02*
Y214764D01*
G01X35433Y157480D02*
G03I-7874J0D01*
G01X17879Y229882D02*
G03X17289Y229291I0J-590D01*
G01X17520Y212441D02*
G03X18110Y211850I591J0D01*
G01X17520Y217559D02*
G03X16929Y218150I-591J0D01*
G01X11417Y223583D02*
G03X11220Y223386I0J-197D01*
G01Y222047D02*
G03X11417Y221850I197J0D01*
G01Y219882D02*
G03X11220Y219685I0J-197D01*
G01Y218346D02*
G03X11417Y218150I197J1D01*
G01X-2953Y226969D02*
G03Y214764I0J-6103D01*
G01X16501Y225945D02*
X13189Y223583D01*
G01X28740Y227323D02*
X30315Y228898D01*
G01X28740Y215748D02*
X30315Y218583D01*
G01X11220Y225157D02*
X14134Y231850D01*
G01X28740Y209291D02*
Y232441D01*
G01X27559Y227879D02*
Y214698D01*
G01X17520Y217559D02*
Y212441D01*
G01X17289Y229291D02*
Y225945D01*
G01X11417Y218150D02*
Y215943D01*
G01Y221850D02*
Y219882D01*
G01X11220Y228346D02*
Y214764D01*
G01Y228896D02*
Y214698D01*
G01X9843Y231299D02*
Y210433D01*
G01X7283Y228346D02*
Y214764D01*
G01X6496Y227756D02*
Y214764D01*
G01X5906Y207677D02*
Y234055D01*
G01X0Y226969D02*
Y342461D01*
G01Y214764D02*
Y226969D01*
G01Y214764D02*
Y226969D01*
G01X-2953Y214764D02*
Y226969D01*
G01X-5906Y226197D02*
Y215535D01*
G01X14055Y209882D02*
X11220Y216396D01*
G01X30315Y223150D02*
X28740Y225984D01*
G01X30315Y212913D02*
X28740Y214803D01*
G01X5906Y234055D02*
X32677D01*
G01X28740Y232441D02*
X30315D01*
G01X5906Y232047D02*
X30315D01*
G01Y231850D02*
X14134D01*
G01X30315Y231299D02*
X9843D01*
G01X17879Y229882D02*
X30315D01*
G01X11220Y228896D02*
X5906D01*
G01X7283Y228346D02*
X11220D01*
G01X27559Y227879D02*
X11220D01*
G01X6496Y227756D02*
X7283D01*
G01X5906Y226969D02*
X-2953D01*
G01X6496D02*
X5906D01*
G01X17289Y225945D02*
X16501D01*
G01X13189Y223583D02*
X11417D01*
G01Y221850D02*
X30315D01*
G01Y219882D02*
X11417D01*
G01Y218150D02*
X16929D01*
G01X5906Y214764D02*
X11220D01*
G01X5906D02*
X-2953D01*
G01X11220Y214724D02*
X5906D01*
G01X27559Y214698D02*
X11220D01*
G01X18110Y211850D02*
X30315D01*
G01Y210433D02*
X9843D01*
G01X30315Y209882D02*
X14055D01*
G01X5906Y209685D02*
X30315D01*
G01X28740Y209291D02*
X30315D01*
G01X5906Y207677D02*
X32677D01*
G01X0Y226969D02*
Y342461D01*
G01Y226969D02*
Y342461D01*
G01Y214764D02*
Y226969D01*
G01Y214764D02*
Y226969D01*
G01Y214764D02*
Y226969D01*
G01Y214764D02*
Y226969D01*
G01Y278740D02*
G03X-7874I-3937J0D01*
G01X0D02*
G03X-7874I-3937J0D01*
G01X17520Y340138D02*
G03X18110Y339547I591J0D01*
G01X-2953Y354665D02*
G03Y342461I0J-6102D01*
G01X28740Y336988D02*
Y360138D01*
G01X27559Y355575D02*
Y342395D01*
G01X17520Y345256D02*
Y340138D01*
G01X11220Y356593D02*
Y342395D01*
G01Y356043D02*
Y342461D01*
G01X9843Y358996D02*
Y338130D01*
G01X7283Y356043D02*
Y342461D01*
G01X6496Y355453D02*
Y342461D01*
G01X5906Y335374D02*
Y361752D01*
G01X0Y342461D02*
Y354665D01*
G01Y342461D02*
Y354665D01*
G01X-2953Y342461D02*
Y354665D01*
G01X-5906Y353894D02*
Y343232D01*
G01X14055Y337579D02*
X11220Y344093D01*
G01X30315Y340610D02*
X28740Y342500D01*
G01X5906Y342461D02*
X11220D01*
G01X5906D02*
X-2953D01*
G01X11220Y342421D02*
X5906D01*
G01X27559Y342395D02*
X11220D01*
G01X18110Y339547D02*
X30315D01*
G01Y338130D02*
X9843D01*
G01X30315Y337579D02*
X14055D01*
G01X5906Y337382D02*
X30315D01*
G01X28740Y336988D02*
X30315D01*
G01X5906Y335374D02*
X32677D01*
G01X0Y342461D02*
Y354665D01*
G01Y342461D02*
Y354665D01*
G01X-7874Y309449D02*
G03X0I3937J0D01*
G01X-7874D02*
G03X0I3937J0D01*
G01X17879Y357579D02*
G03X17289Y356988I1J-591D01*
G01X17520Y345256D02*
G03X16929Y345846I-590J0D01*
G01X11417Y351280D02*
G03X11220Y351083I0J-197D01*
G01Y349744D02*
G03X11417Y349547I197J0D01*
G01Y347579D02*
G03X11220Y347382I0J-197D01*
G01Y346043D02*
G03X11417Y345846I197J0D01*
G01X16501Y353642D02*
X13189Y351280D01*
G01X28740Y355020D02*
X30315Y356594D01*
G01X28740Y343445D02*
X30315Y346280D01*
G01X11220Y352854D02*
X14134Y359547D01*
G01X17289Y356988D02*
Y353642D01*
G01X11417Y345846D02*
Y343640D01*
G01Y349547D02*
Y347579D01*
G01X0Y354665D02*
Y476339D01*
G01X30315Y350846D02*
X28740Y353681D01*
G01X5906Y361752D02*
X32677D01*
G01X28740Y360138D02*
X30315D01*
G01X5906Y359744D02*
X30315D01*
G01Y359547D02*
X14134D01*
G01X30315Y358996D02*
X9843D01*
G01X17879Y357579D02*
X30315D01*
G01X11220Y356593D02*
X5906D01*
G01X7283Y356043D02*
X11220D01*
G01X27559Y355575D02*
X11220D01*
G01X6496Y355453D02*
X7283D01*
G01X5906Y354665D02*
X-2953D01*
G01X6496D02*
X5906D01*
G01X17289Y353642D02*
X16501D01*
G01X13189Y351280D02*
X11417D01*
G01Y349547D02*
X30315D01*
G01Y347579D02*
X11417D01*
G01Y345846D02*
X16929D01*
G01X0Y354665D02*
Y476339D01*
G01Y354665D02*
Y476339D01*
G01X13907Y482598D02*
G03Y480079I1998J-1259D01*
G01Y492598D02*
G03Y490079I1998J-1260D01*
G01X37008Y458032D02*
G03I-7087J0D01*
G01X16575Y482008D02*
X17165Y482598D01*
G01X15236Y480669D02*
X14646Y480079D01*
G01X16575Y492008D02*
X17165Y492598D01*
G01X15236Y490669D02*
X14646Y490079D01*
G01X17165Y482598D02*
Y480079D01*
G01Y492598D02*
Y490079D01*
G01X16575Y490669D02*
Y492008D01*
G01Y480669D02*
Y482008D01*
G01X15236Y490669D02*
Y492008D01*
G01Y480669D02*
Y482008D01*
G01X14646Y482598D02*
Y480079D01*
G01Y492598D02*
Y490079D01*
G01X13661Y482598D02*
Y480079D01*
G01Y492598D02*
Y490079D01*
G01X10000Y476339D02*
Y526339D01*
G01X8819D02*
Y476339D01*
G01X0D02*
Y526339D01*
G01Y476339D02*
Y526339D01*
G01Y476339D02*
Y526339D01*
G01X15236Y492008D02*
X14646Y492598D01*
G01X17165Y490079D02*
X16575Y490669D01*
G01X15236Y482008D02*
X14646Y482598D01*
G01X17165Y480079D02*
X16575Y480669D01*
G01X10000Y495551D02*
X0D01*
G01X10000Y494764D02*
X0D01*
G01X10000Y492598D02*
X8819D01*
G01X17165D02*
X10000D01*
G01X16575Y492008D02*
X15236D01*
G01Y490669D02*
X16575D01*
G01X10000Y490079D02*
X8819D01*
G01X17165D02*
X10000D01*
G01X0Y487913D02*
X10000D01*
G01X0Y487126D02*
X10000D01*
G01Y485551D02*
X0D01*
G01X10000Y484764D02*
X0D01*
G01X10000Y482598D02*
X8819D01*
G01X17165D02*
X10000D01*
G01X16575Y482008D02*
X15236D01*
G01Y480669D02*
X16575D01*
G01X10000Y480079D02*
X8819D01*
G01X17165D02*
X10000D01*
G01X0Y477913D02*
X10000D01*
G01X0Y477126D02*
X10000D01*
G01X0Y476339D02*
X10000D01*
G01X0D02*
Y526339D01*
G01Y476339D02*
Y526339D01*
G01Y476339D02*
Y526339D01*
G01X13907Y502598D02*
G03Y500079I1998J-1259D01*
G01Y512598D02*
G03Y510079I1998J-1259D01*
G01Y522598D02*
G03Y520079I1998J-1259D01*
G01X37008Y544646D02*
G03I-7087J0D01*
G01X19004Y521311D02*
X18878Y521270D01*
G01Y521516D02*
X19004Y521557D01*
G01X18711Y521393D02*
X18878Y521516D01*
G01Y521270D02*
X18795Y521188D01*
G01X16575Y502008D02*
X17165Y502598D01*
G01X15236Y500669D02*
X14646Y500079D01*
G01X16575Y512008D02*
X17165Y512598D01*
G01X15236Y510669D02*
X14646Y510079D01*
G01X16575Y522008D02*
X17165Y522598D01*
G01X15236Y520669D02*
X14646Y520079D01*
G01X18585Y521229D02*
X18711Y521393D01*
G01X18795Y521188D02*
X18753Y521065D01*
G01X18543Y521024D02*
X18585Y521229D01*
G01X20512Y520285D02*
Y520039D01*
G01Y522377D02*
Y522131D01*
G01X19632Y521024D02*
Y520285D01*
G01X19381D02*
Y521065D01*
G01X18753D02*
Y520285D01*
G01X18543Y522131D02*
Y522377D01*
G01Y520039D02*
Y521024D01*
G01X17165Y502598D02*
Y500079D01*
G01Y512598D02*
Y510079D01*
G01Y522598D02*
Y520079D01*
G01X16575Y520669D02*
Y522008D01*
G01Y510669D02*
Y512008D01*
G01Y500669D02*
Y502008D01*
G01X15236Y520669D02*
Y522008D01*
G01Y510669D02*
Y512008D01*
G01Y500669D02*
Y502008D01*
G01X14646Y502598D02*
Y500079D01*
G01Y512598D02*
Y510079D01*
G01Y522598D02*
Y520079D01*
G01X13661Y502598D02*
Y500079D01*
G01Y512598D02*
Y510079D01*
G01Y522598D02*
Y520079D01*
G01X0Y526339D02*
Y736181D01*
G01X19590Y521229D02*
X19632Y521024D01*
G01X19381Y521065D02*
X19339Y521188D01*
G01X19465Y521393D02*
X19590Y521229D01*
G01X15236Y522008D02*
X14646Y522598D01*
G01X17165Y520079D02*
X16575Y520669D01*
G01X19339Y521188D02*
X19255Y521270D01*
G01X15236Y512008D02*
X14646Y512598D01*
G01X17165Y510079D02*
X16575Y510669D01*
G01X15236Y502008D02*
X14646Y502598D01*
G01X17165Y500079D02*
X16575Y500669D01*
G01X18878Y522131D02*
X19172Y521885D01*
G01X18836D02*
X18543Y522131D01*
G01X19297Y521516D02*
X19465Y521393D01*
G01X19172Y521557D02*
X19297Y521516D01*
G01X19255Y521270D02*
X19130Y521311D01*
G01X0Y526339D02*
X10000D01*
G01Y525551D02*
X0D01*
G01X10000Y524764D02*
X0D01*
G01X10000Y522598D02*
X8819D01*
G01X17165D02*
X10000D01*
G01X18543Y522377D02*
X20512D01*
G01Y522131D02*
X18878D01*
G01X16575Y522008D02*
X15236D01*
G01X19172Y521885D02*
X18836D01*
G01X19004Y521557D02*
X19172D01*
G01X19130Y521311D02*
X19004D01*
G01X15236Y520669D02*
X16575D01*
G01X18753Y520285D02*
X19381D01*
G01X19632D02*
X20512D01*
G01X10000Y520079D02*
X8819D01*
G01X17165D02*
X10000D01*
G01X20512Y520039D02*
X18543D01*
G01X0Y517913D02*
X10000D01*
G01X0Y517126D02*
X10000D01*
G01Y515551D02*
X0D01*
G01X10000Y514764D02*
X0D01*
G01X10000Y512598D02*
X8819D01*
G01X17165D02*
X10000D01*
G01X16575Y512008D02*
X15236D01*
G01Y510669D02*
X16575D01*
G01X10000Y510079D02*
X8819D01*
G01X17165D02*
X10000D01*
G01X0Y507913D02*
X10000D01*
G01X0Y507126D02*
X10000D01*
G01Y505551D02*
X0D01*
G01X10000Y504764D02*
X0D01*
G01X10000Y502598D02*
X8819D01*
G01X17165D02*
X10000D01*
G01X16575Y502008D02*
X15236D01*
G01Y500669D02*
X16575D01*
G01X10000Y500079D02*
X8819D01*
G01X17165D02*
X10000D01*
G01X0Y497913D02*
X10000D01*
G01X0Y497126D02*
X10000D01*
G01X0Y526339D02*
Y736181D01*
G01Y526339D02*
Y736181D01*
G01Y545669D02*
G03X-7874I-3937J0D01*
G01X0D02*
G03X-7874I-3937J0D01*
G01Y576378D02*
G03X0I3937J0D01*
G01X-7874D02*
G03X0I3937J0D01*
G01X34449Y629921D02*
G03I-6890J0D01*
G01X13907Y742441D02*
G03Y739921I1998J-1260D01*
G01Y752441D02*
G03Y749921I1998J-1260D01*
G01X37008Y717874D02*
G03I-7087J0D01*
G01X16575Y741850D02*
X17165Y742441D01*
G01X15236Y740512D02*
X14646Y739921D01*
G01X16575Y751850D02*
X17165Y752441D01*
G01X15236Y750512D02*
X14646Y749921D01*
G01X17165Y742441D02*
Y739921D01*
G01Y752441D02*
Y749921D01*
G01X16575Y750512D02*
Y751850D01*
G01Y740512D02*
Y741850D01*
G01X15236Y750512D02*
Y751850D01*
G01Y740512D02*
Y741850D01*
G01X14646Y742441D02*
Y739921D01*
G01Y752441D02*
Y749921D01*
G01X13661Y742441D02*
Y739921D01*
G01Y752441D02*
Y749921D01*
G01X10000Y736181D02*
Y786181D01*
G01X8819D02*
Y736181D01*
G01X0D02*
Y786181D01*
G01Y736181D02*
Y786181D01*
G01Y736181D02*
Y786181D01*
G01X15236Y751850D02*
X14646Y752441D01*
G01X17165Y749921D02*
X16575Y750512D01*
G01X15236Y741850D02*
X14646Y742441D01*
G01X17165Y739921D02*
X16575Y740512D01*
G01Y751850D02*
X15236D01*
G01Y750512D02*
X16575D01*
G01X10000Y749921D02*
X8819D01*
G01X17165D02*
X10000D01*
G01X0Y747756D02*
X10000D01*
G01X0Y746969D02*
X10000D01*
G01Y745394D02*
X0D01*
G01X10000Y744606D02*
X0D01*
G01X10000Y742441D02*
X8819D01*
G01X17165D02*
X10000D01*
G01X16575Y741850D02*
X15236D01*
G01Y740512D02*
X16575D01*
G01X10000Y739921D02*
X8819D01*
G01X17165D02*
X10000D01*
G01X0Y737756D02*
X10000D01*
G01X0Y736969D02*
X10000D01*
G01X0Y736181D02*
X10000D01*
G01X0D02*
Y786181D01*
G01Y736181D02*
Y786181D01*
G01Y736181D02*
Y786181D01*
G01X13907Y762441D02*
G03Y759921I1998J-1260D01*
G01Y772441D02*
G03Y769921I1998J-1260D01*
G01Y782441D02*
G03Y779921I1998J-1260D01*
G01X37008Y804488D02*
G03I-7087J0D01*
G01X19004Y781153D02*
X18878Y781112D01*
G01Y781358D02*
X19004Y781399D01*
G01X18711Y781235D02*
X18878Y781358D01*
G01Y781112D02*
X18795Y781030D01*
G01X16575Y761850D02*
X17165Y762441D01*
G01X15236Y760512D02*
X14646Y759921D01*
G01X16575Y771850D02*
X17165Y772441D01*
G01X15236Y770512D02*
X14646Y769921D01*
G01X16575Y781850D02*
X17165Y782441D01*
G01X15236Y780512D02*
X14646Y779921D01*
G01X18585Y781071D02*
X18711Y781235D01*
G01X18795Y781030D02*
X18753Y780907D01*
G01X18543Y780866D02*
X18585Y781071D01*
G01X19590D02*
X19632Y780866D01*
G01X20512Y782219D02*
Y781973D01*
G01Y780128D02*
Y779882D01*
G01X19632Y780866D02*
Y780128D01*
G01X19381D02*
Y780907D01*
G01X18753D02*
Y780128D01*
G01X18543Y781973D02*
Y782219D01*
G01Y779882D02*
Y780866D01*
G01X17165Y762441D02*
Y759921D01*
G01Y772441D02*
Y769921D01*
G01Y782441D02*
Y779921D01*
G01X16575Y780512D02*
Y781850D01*
G01Y770512D02*
Y771850D01*
G01Y760512D02*
Y761850D01*
G01X15236Y780512D02*
Y781850D01*
G01Y770512D02*
Y771850D01*
G01Y760512D02*
Y761850D01*
G01X14646Y762441D02*
Y759921D01*
G01Y772441D02*
Y769921D01*
G01Y782441D02*
Y779921D01*
G01X13661Y762441D02*
Y759921D01*
G01Y772441D02*
Y769921D01*
G01Y782441D02*
Y779921D01*
G01X0Y786181D02*
Y907815D01*
G01X19381Y780907D02*
X19339Y781030D01*
G01X19465Y781235D02*
X19590Y781071D01*
G01X15236Y781850D02*
X14646Y782441D01*
G01X17165Y779921D02*
X16575Y780512D01*
G01X15236Y771850D02*
X14646Y772441D01*
G01X17165Y769921D02*
X16575Y770512D01*
G01X17165Y759921D02*
X16575Y760512D01*
G01X15236Y761850D02*
X14646Y762441D01*
G01X19339Y781030D02*
X19255Y781112D01*
G01X18878Y781973D02*
X19172Y781727D01*
G01X18836D02*
X18543Y781973D01*
G01X19297Y781358D02*
X19465Y781235D01*
G01X19172Y781399D02*
X19297Y781358D01*
G01X19255Y781112D02*
X19130Y781153D01*
G01X0Y786181D02*
X10000D01*
G01Y785394D02*
X0D01*
G01X10000Y784606D02*
X0D01*
G01X10000Y782441D02*
X8819D01*
G01X17165D02*
X10000D01*
G01X18543Y782219D02*
X20512D01*
G01Y781973D02*
X18878D01*
G01X16575Y781850D02*
X15236D01*
G01X19172Y781727D02*
X18836D01*
G01X19004Y781399D02*
X19172D01*
G01X19130Y781153D02*
X19004D01*
G01X15236Y780512D02*
X16575D01*
G01X18753Y780128D02*
X19381D01*
G01X19632D02*
X20512D01*
G01X10000Y779921D02*
X8819D01*
G01X17165D02*
X10000D01*
G01X20512Y779882D02*
X18543D01*
G01X0Y777756D02*
X10000D01*
G01X0Y776969D02*
X10000D01*
G01Y775394D02*
X0D01*
G01X10000Y774606D02*
X0D01*
G01X10000Y772441D02*
X8819D01*
G01X17165D02*
X10000D01*
G01X16575Y771850D02*
X15236D01*
G01Y770512D02*
X16575D01*
G01X10000Y769921D02*
X8819D01*
G01X17165D02*
X10000D01*
G01X0Y767756D02*
X10000D01*
G01X0Y766969D02*
X10000D01*
G01Y765394D02*
X0D01*
G01X10000Y764606D02*
X0D01*
G01X10000Y762441D02*
X8819D01*
G01X17165D02*
X10000D01*
G01X16575Y761850D02*
X15236D01*
G01Y760512D02*
X16575D01*
G01X10000Y759921D02*
X8819D01*
G01X17165D02*
X10000D01*
G01X0Y757756D02*
X10000D01*
G01X0Y756969D02*
X10000D01*
G01Y755394D02*
X0D01*
G01X10000Y754606D02*
X0D01*
G01X10000Y752441D02*
X8819D01*
G01X17165D02*
X10000D01*
G01X0Y786181D02*
Y907815D01*
G01Y786181D02*
Y907815D01*
G01Y831496D02*
G03X-7874I-3937J0D01*
G01X0D02*
G03X-7874I-3937J0D01*
G01X17520Y905492D02*
G03X18110Y904902I590J0D01*
G01X14055Y902933D02*
X11220Y909447D01*
G01X18110Y904902D02*
X30315D01*
G01Y903484D02*
X9843D01*
G01X30315Y902933D02*
X14055D01*
G01X5906Y902736D02*
X30315D01*
G01X28740Y902343D02*
X30315D01*
G01X5906Y900728D02*
X32677D01*
G01X28740Y902343D02*
Y925492D01*
G01X17520Y910610D02*
Y905492D01*
G01X9843Y924350D02*
Y903484D01*
G01X5906Y900728D02*
Y927106D01*
G01X-7874Y862205D02*
G03X0I3937J0D01*
G01X-7874D02*
G03X0I3937J0D01*
G01X17879Y922933D02*
G03X17289Y922343I0J-590D01*
G01X17520Y910610D02*
G03X16929Y911201I-591J0D01*
G01X11417Y916634D02*
G03X11220Y916437I0J-197D01*
G01Y915098D02*
G03X11417Y914902I197J1D01*
G01Y912933D02*
G03X11220Y912736I0J-197D01*
G01Y911398D02*
G03X11417Y911201I197J0D01*
G01X-2953Y920020D02*
G03Y907815I0J-6103D01*
G01X16501Y918996D02*
X13189Y916634D01*
G01X5906Y927106D02*
X32677D01*
G01X28740Y920374D02*
X30315Y921949D01*
G01X28740Y908799D02*
X30315Y911634D01*
G01X11220Y918209D02*
X14134Y924902D01*
G01X30315Y916201D02*
X28740Y919035D01*
G01X30315Y905965D02*
X28740Y907854D01*
G01Y925492D02*
X30315D01*
G01X5906Y925098D02*
X30315D01*
G01Y924902D02*
X14134D01*
G01X30315Y924350D02*
X9843D01*
G01X17879Y922933D02*
X30315D01*
G01X11220Y921947D02*
X5906D01*
G01X7283Y921398D02*
X11220D01*
G01X27559Y920930D02*
X11220D01*
G01X6496Y920807D02*
X7283D01*
G01X5906Y920020D02*
X-2953D01*
G01X6496D02*
X5906D01*
G01X17289Y918996D02*
X16501D01*
G01X13189Y916634D02*
X11417D01*
G01Y914902D02*
X30315D01*
G01Y912933D02*
X11417D01*
G01Y911201D02*
X16929D01*
G01X5906Y907815D02*
X11220D01*
G01X5906D02*
X-2953D01*
G01X11220Y907776D02*
X5906D01*
G01X27559Y907749D02*
X11220D01*
G01X27559Y920930D02*
Y907749D01*
G01X17289Y922343D02*
Y918996D01*
G01X11417Y911201D02*
Y908995D01*
G01Y914902D02*
Y912933D01*
G01X11220Y921947D02*
Y907749D01*
G01Y921398D02*
Y907815D01*
G01X7283Y921398D02*
Y907815D01*
G01X6496Y920807D02*
Y907815D01*
G01X0Y920020D02*
Y1048484D01*
G01Y907815D02*
Y920020D01*
G01Y907815D02*
Y920020D01*
G01X-2953Y907815D02*
Y920020D01*
G01X-5906Y919248D02*
Y908587D01*
G01X0Y920020D02*
Y1048484D01*
G01Y920020D02*
Y1048484D01*
G01Y907815D02*
Y920020D01*
G01Y907815D02*
Y920020D01*
G01X17520Y1046161D02*
G03X18110Y1045571I590J0D01*
G01X17520Y1051280D02*
G03X16929Y1051870I-591J-1D01*
G01X11417Y1057303D02*
G03X11220Y1057106I0J-197D01*
G01Y1055768D02*
G03X11417Y1055571I197J0D01*
G01Y1053602D02*
G03X11220Y1053406I0J-197D01*
G01Y1052067D02*
G03X11417Y1051870I197J0D01*
G01X-2953Y1060689D02*
G03Y1048484I0J-6103D01*
G01X13189Y1057303D02*
X11417D01*
G01Y1055571D02*
X30315D01*
G01Y1053602D02*
X11417D01*
G01Y1051870D02*
X16929D01*
G01X5906Y1048484D02*
X11220D01*
G01X5906D02*
X-2953D01*
G01X11220Y1048445D02*
X5906D01*
G01X27559Y1048418D02*
X11220D01*
G01X18110Y1045571D02*
X30315D01*
G01Y1044154D02*
X9843D01*
G01X30315Y1043602D02*
X14055D01*
G01X5906Y1043406D02*
X30315D01*
G01X28740Y1043012D02*
X30315D01*
G01X5906Y1041398D02*
X32677D01*
G01X14055Y1043602D02*
X11220Y1050116D01*
G01X30315Y1056870D02*
X28740Y1059705D01*
G01X30315Y1046634D02*
X28740Y1048524D01*
G01X16501Y1059665D02*
X13189Y1057303D01*
G01X28740Y1049469D02*
X30315Y1052303D01*
G01X11220Y1058878D02*
X14134Y1065571D01*
G01X28740Y1043012D02*
Y1066161D01*
G01X27559Y1061599D02*
Y1048418D01*
G01X17520Y1051280D02*
Y1046161D01*
G01X11417Y1051870D02*
Y1049664D01*
G01Y1055571D02*
Y1053602D01*
G01X11220Y1062067D02*
Y1048484D01*
G01Y1062617D02*
Y1048418D01*
G01X9843Y1065020D02*
Y1044154D01*
G01X7283Y1062067D02*
Y1048484D01*
G01X6496Y1061476D02*
Y1048484D01*
G01X5906Y1041398D02*
Y1067776D01*
G01X0Y1048484D02*
Y1060689D01*
G01Y1048484D02*
Y1060689D01*
G01X-2953Y1048484D02*
Y1060689D01*
G01X-5906Y1059917D02*
Y1049256D01*
G01X0Y1048484D02*
Y1060689D01*
G01Y1048484D02*
Y1060689D01*
G01X17879Y1063602D02*
G03X17289Y1063012I0J-590D01*
G01X5906Y1067776D02*
X32677D01*
G01X28740Y1066161D02*
X30315D01*
G01X5906Y1065768D02*
X30315D01*
G01Y1065571D02*
X14134D01*
G01X30315Y1065020D02*
X9843D01*
G01X17879Y1063602D02*
X30315D01*
G01X11220Y1062617D02*
X5906D01*
G01X7283Y1062067D02*
X11220D01*
G01X27559Y1061599D02*
X11220D01*
G01X6496Y1061476D02*
X7283D01*
G01X5906Y1060689D02*
X-2953D01*
G01X6496D02*
X5906D01*
G01X17289Y1059665D02*
X16501D01*
G01X28740Y1061043D02*
X30315Y1062618D01*
G01X17289Y1063012D02*
Y1059665D01*
G01X0Y1060689D02*
Y1182323D01*
G01Y1060689D02*
Y1182323D01*
G01Y1060689D02*
Y1182323D01*
G01Y1106299D02*
G03X-7874I-3937J0D01*
G01X0D02*
G03X-7874I-3937J0D01*
G01X37008Y1164016D02*
G03I-7087J0D01*
G01X-7874Y1137008D02*
G03X0I3937J0D01*
G01X-7874D02*
G03X0I3937J0D01*
G01X13907Y1188583D02*
G03Y1186063I1998J-1260D01*
G01Y1198583D02*
G03Y1196063I1998J-1260D01*
G01Y1208583D02*
G03Y1206063I1998J-1260D01*
G01X10000Y1211535D02*
X0D01*
G01X10000Y1210748D02*
X0D01*
G01X10000Y1208583D02*
X8819D01*
G01X17165D02*
X10000D01*
G01X16575Y1207992D02*
X15236D01*
G01Y1206654D02*
X16575D01*
G01X10000Y1206063D02*
X8819D01*
G01X17165D02*
X10000D01*
G01X0Y1203898D02*
X10000D01*
G01X0Y1203110D02*
X10000D01*
G01Y1201535D02*
X0D01*
G01X10000Y1200748D02*
X0D01*
G01X10000Y1198583D02*
X8819D01*
G01X17165D02*
X10000D01*
G01X16575Y1197992D02*
X15236D01*
G01Y1196654D02*
X16575D01*
G01X10000Y1196063D02*
X8819D01*
G01X17165D02*
X10000D01*
G01X0Y1193898D02*
X10000D01*
G01X0Y1193110D02*
X10000D01*
G01Y1191535D02*
X0D01*
G01X10000Y1190748D02*
X0D01*
G01X10000Y1188583D02*
X8819D01*
G01X17165D02*
X10000D01*
G01X16575Y1187992D02*
X15236D01*
G01Y1186654D02*
X16575D01*
G01X10000Y1186063D02*
X8819D01*
G01X17165D02*
X10000D01*
G01X0Y1183898D02*
X10000D01*
G01X0Y1183110D02*
X10000D01*
G01X0Y1182323D02*
X10000D01*
G01X15236Y1207992D02*
X14646Y1208583D01*
G01X17165Y1206063D02*
X16575Y1206654D01*
G01X15236Y1197992D02*
X14646Y1198583D01*
G01X17165Y1196063D02*
X16575Y1196654D01*
G01X17165Y1186063D02*
X16575Y1186654D01*
G01X15236Y1187992D02*
X14646Y1188583D01*
G01X17165D02*
Y1186063D01*
G01Y1198583D02*
Y1196063D01*
G01Y1208583D02*
Y1206063D01*
G01X16575Y1206654D02*
Y1207992D01*
G01Y1196654D02*
Y1197992D01*
G01Y1186654D02*
Y1187992D01*
G01X15236Y1206654D02*
Y1207992D01*
G01Y1196654D02*
Y1197992D01*
G01Y1186654D02*
Y1187992D01*
G01X14646Y1188583D02*
Y1186063D01*
G01Y1198583D02*
Y1196063D01*
G01Y1208583D02*
Y1206063D01*
G01X13661Y1188583D02*
Y1186063D01*
G01Y1198583D02*
Y1196063D01*
G01Y1208583D02*
Y1206063D01*
G01X10000Y1182323D02*
Y1232323D01*
G01X8819D02*
Y1182323D01*
G01X0D02*
Y1232323D01*
G01Y1182323D02*
Y1232323D01*
G01Y1182323D02*
Y1232323D01*
G01X16575Y1187992D02*
X17165Y1188583D01*
G01X15236Y1186654D02*
X14646Y1186063D01*
G01X16575Y1197992D02*
X17165Y1198583D01*
G01X15236Y1196654D02*
X14646Y1196063D01*
G01X16575Y1207992D02*
X17165Y1208583D01*
G01X15236Y1206654D02*
X14646Y1206063D01*
G01X0Y1182323D02*
Y1232323D01*
G01Y1182323D02*
Y1232323D01*
G01Y1182323D02*
Y1232323D01*
G01X13907Y1218583D02*
G03Y1216063I1998J-1260D01*
G01Y1228583D02*
G03Y1226063I1998J-1260D01*
G01X37008Y1250630D02*
G03I-7087J0D01*
G01X19172Y1227541D02*
X19297Y1227500D01*
G01X19255Y1227254D02*
X19130Y1227295D01*
G01X0Y1232323D02*
X10000D01*
G01Y1231535D02*
X0D01*
G01X10000Y1230748D02*
X0D01*
G01X10000Y1228583D02*
X8819D01*
G01X17165D02*
X10000D01*
G01X18543Y1228361D02*
X20512D01*
G01Y1228115D02*
X18878D01*
G01X16575Y1227992D02*
X15236D01*
G01X19172Y1227869D02*
X18836D01*
G01X19004Y1227541D02*
X19172D01*
G01X19130Y1227295D02*
X19004D01*
G01X15236Y1226654D02*
X16575D01*
G01X18753Y1226270D02*
X19381D01*
G01X19632D02*
X20512D01*
G01X10000Y1226063D02*
X8819D01*
G01X17165D02*
X10000D01*
G01X20512Y1226024D02*
X18543D01*
G01X0Y1223898D02*
X10000D01*
G01X0Y1223110D02*
X10000D01*
G01Y1221535D02*
X0D01*
G01X10000Y1220748D02*
X0D01*
G01X10000Y1218583D02*
X8819D01*
G01X17165D02*
X10000D01*
G01X16575Y1217992D02*
X15236D01*
G01Y1216654D02*
X16575D01*
G01X10000Y1216063D02*
X8819D01*
G01X17165D02*
X10000D01*
G01X0Y1213898D02*
X10000D01*
G01X0Y1213110D02*
X10000D01*
G01X19297Y1227500D02*
X19465Y1227377D01*
G01D02*
X19590Y1227213D01*
G01X15236Y1227992D02*
X14646Y1228583D01*
G01X17165Y1226063D02*
X16575Y1226654D01*
G01X15236Y1217992D02*
X14646Y1218583D01*
G01X17165Y1216063D02*
X16575Y1216654D01*
G01X19339Y1227172D02*
X19255Y1227254D01*
G01X18878Y1228115D02*
X19172Y1227869D01*
G01X18836D02*
X18543Y1228115D01*
G01X19381Y1227049D02*
X19339Y1227172D01*
G01X19590Y1227213D02*
X19632Y1227008D01*
G01X18543D02*
X18585Y1227213D01*
G01X20512Y1226270D02*
Y1226024D01*
G01Y1228361D02*
Y1228115D01*
G01X19632Y1227008D02*
Y1226270D01*
G01X19381D02*
Y1227049D01*
G01X18753D02*
Y1226270D01*
G01X18543Y1228115D02*
Y1228361D01*
G01Y1226024D02*
Y1227008D01*
G01X17165Y1218583D02*
Y1216063D01*
G01Y1228583D02*
Y1226063D01*
G01X16575Y1226654D02*
Y1227992D01*
G01Y1216654D02*
Y1217992D01*
G01X15236Y1226654D02*
Y1227992D01*
G01Y1216654D02*
Y1217992D01*
G01X14646Y1218583D02*
Y1216063D01*
G01Y1228583D02*
Y1226063D01*
G01X13661Y1218583D02*
Y1216063D01*
G01Y1228583D02*
Y1226063D01*
G01X0Y1232323D02*
Y1442165D01*
G01X18795Y1227172D02*
X18753Y1227049D01*
G01X19004Y1227295D02*
X18878Y1227254D01*
G01Y1227500D02*
X19004Y1227541D01*
G01X18711Y1227377D02*
X18878Y1227500D01*
G01Y1227254D02*
X18795Y1227172D01*
G01X16575Y1217992D02*
X17165Y1218583D01*
G01X15236Y1216654D02*
X14646Y1216063D01*
G01X16575Y1227992D02*
X17165Y1228583D01*
G01X15236Y1226654D02*
X14646Y1226063D01*
G01X18585Y1227213D02*
X18711Y1227377D01*
G01X0Y1232323D02*
Y1442165D01*
G01Y1232323D02*
Y1442165D01*
G01X24606Y1338583D02*
G03I-6889J0D01*
G01X37008Y1423858D02*
G03I-7087J0D01*
G01X0Y1392126D02*
G03X-7874I-3937J0D01*
G01X0D02*
G03X-7874I-3937J0D01*
G01X13907Y1448425D02*
G03Y1445905I1998J-1260D01*
G01Y1458425D02*
G03Y1455905I1998J-1260D01*
G01Y1468425D02*
G03Y1465905I1998J-1260D01*
G01X16575Y1467835D02*
X15236D01*
G01Y1466496D02*
X16575D01*
G01X10000Y1465906D02*
X8819D01*
G01X17165D02*
X10000D01*
G01X0Y1463740D02*
X10000D01*
G01X0Y1462953D02*
X10000D01*
G01Y1461378D02*
X0D01*
G01X10000Y1460591D02*
X0D01*
G01X10000Y1458425D02*
X8819D01*
G01X17165D02*
X10000D01*
G01X16575Y1457835D02*
X15236D01*
G01Y1456496D02*
X16575D01*
G01X10000Y1455906D02*
X8819D01*
G01X17165D02*
X10000D01*
G01X0Y1453740D02*
X10000D01*
G01X0Y1452953D02*
X10000D01*
G01Y1451378D02*
X0D01*
G01X10000Y1450591D02*
X0D01*
G01X10000Y1448425D02*
X8819D01*
G01X17165D02*
X10000D01*
G01X16575Y1447835D02*
X15236D01*
G01Y1446496D02*
X16575D01*
G01X10000Y1445906D02*
X8819D01*
G01X17165D02*
X10000D01*
G01X0Y1443740D02*
X10000D01*
G01X0Y1442953D02*
X10000D01*
G01X0Y1442165D02*
X10000D01*
G01X15236Y1467835D02*
X14646Y1468425D01*
G01X17165Y1465906D02*
X16575Y1466496D01*
G01X15236Y1457835D02*
X14646Y1458425D01*
G01X17165Y1455906D02*
X16575Y1456496D01*
G01X15236Y1447835D02*
X14646Y1448425D01*
G01X17165Y1445906D02*
X16575Y1446496D01*
G01X17165Y1448425D02*
Y1445906D01*
G01Y1458425D02*
Y1455906D01*
G01Y1468425D02*
Y1465906D01*
G01X16575Y1466496D02*
Y1467835D01*
G01Y1456496D02*
Y1457835D01*
G01Y1446496D02*
Y1447835D01*
G01X15236Y1466496D02*
Y1467835D01*
G01Y1456496D02*
Y1457835D01*
G01Y1446496D02*
Y1447835D01*
G01X14646Y1448425D02*
Y1445906D01*
G01Y1458425D02*
Y1455906D01*
G01Y1468425D02*
Y1465906D01*
G01X13661Y1448425D02*
Y1445906D01*
G01Y1458425D02*
Y1455906D01*
G01Y1468425D02*
Y1465906D01*
G01X10000Y1442165D02*
Y1492165D01*
G01X8819D02*
Y1442165D01*
G01X0D02*
Y1492165D01*
G01Y1442165D02*
Y1492165D01*
G01Y1442165D02*
Y1492165D01*
G01X16575Y1447835D02*
X17165Y1448425D01*
G01X15236Y1446496D02*
X14646Y1445906D01*
G01X16575Y1457835D02*
X17165Y1458425D01*
G01X15236Y1456496D02*
X14646Y1455906D01*
G01X16575Y1467835D02*
X17165Y1468425D01*
G01X15236Y1466496D02*
X14646Y1465906D01*
G01X0Y1442165D02*
Y1492165D01*
G01Y1442165D02*
Y1492165D01*
G01Y1442165D02*
Y1492165D01*
G01X-7874Y1422835D02*
G03X0I3937J0D01*
G01X-7874D02*
G03X0I3937J0D01*
G01Y1442165D02*
Y1492165D01*
G01Y1442165D02*
Y1492165D01*
G01X37008Y1510472D02*
G03I-7087J0D01*
G01X13907Y1478425D02*
G03Y1475905I1998J-1260D01*
G01Y1488425D02*
G03Y1485905I1998J-1260D01*
G01X0Y1492165D02*
X10000D01*
G01Y1491378D02*
X0D01*
G01X10000Y1490591D02*
X0D01*
G01X10000Y1488425D02*
X8819D01*
G01X17165D02*
X10000D01*
G01X18543Y1488204D02*
X20512D01*
G01Y1487958D02*
X18878D01*
G01X16575Y1487835D02*
X15236D01*
G01X19172Y1487712D02*
X18836D01*
G01X19004Y1487384D02*
X19172D01*
G01X19130Y1487137D02*
X19004D01*
G01X15236Y1486496D02*
X16575D01*
G01X18753Y1486112D02*
X19381D01*
G01X19632D02*
X20512D01*
G01X10000Y1485906D02*
X8819D01*
G01X17165D02*
X10000D01*
G01X20512Y1485866D02*
X18543D01*
G01X0Y1483740D02*
X10000D01*
G01X0Y1482953D02*
X10000D01*
G01Y1481378D02*
X0D01*
G01X10000Y1480591D02*
X0D01*
G01X10000Y1478425D02*
X8819D01*
G01X17165D02*
X10000D01*
G01X16575Y1477835D02*
X15236D01*
G01Y1476496D02*
X16575D01*
G01X10000Y1475906D02*
X8819D01*
G01X17165D02*
X10000D01*
G01X0Y1473740D02*
X10000D01*
G01X0Y1472953D02*
X10000D01*
G01Y1471378D02*
X0D01*
G01X10000Y1470591D02*
X0D01*
G01X10000Y1468425D02*
X8819D01*
G01X17165D02*
X10000D01*
G01X19172Y1487384D02*
X19297Y1487343D01*
G01X19255Y1487096D02*
X19130Y1487137D01*
G01X19297Y1487343D02*
X19465Y1487219D01*
G01X15236Y1487835D02*
X14646Y1488425D01*
G01X17165Y1485906D02*
X16575Y1486496D01*
G01X15236Y1477835D02*
X14646Y1478425D01*
G01X17165Y1475906D02*
X16575Y1476496D01*
G01X19339Y1487014D02*
X19255Y1487096D01*
G01X18878Y1487958D02*
X19172Y1487712D01*
G01X18836D02*
X18543Y1487958D01*
G01X19465Y1487219D02*
X19590Y1487055D01*
G01X19381Y1486891D02*
X19339Y1487014D01*
G01X19590Y1487055D02*
X19632Y1486850D01*
G01X20512Y1488204D02*
Y1487958D01*
G01Y1486112D02*
Y1485866D01*
G01X19632Y1486850D02*
Y1486112D01*
G01X19381D02*
Y1486891D01*
G01X18753D02*
Y1486112D01*
G01X18543Y1487958D02*
Y1488204D01*
G01Y1485866D02*
Y1486850D01*
G01X17165Y1478425D02*
Y1475906D01*
G01Y1488425D02*
Y1485906D01*
G01X16575Y1486496D02*
Y1487835D01*
G01Y1476496D02*
Y1477835D01*
G01X15236Y1486496D02*
Y1487835D01*
G01Y1476496D02*
Y1477835D01*
G01X14646Y1478425D02*
Y1475906D01*
G01Y1488425D02*
Y1485906D01*
G01X13661Y1478425D02*
Y1475906D01*
G01Y1488425D02*
Y1485906D01*
G01X0Y1492165D02*
Y1613839D01*
G01X18543Y1486850D02*
X18585Y1487055D01*
G01X18795Y1487014D02*
X18753Y1486891D01*
G01X18585Y1487055D02*
X18711Y1487219D01*
G01D02*
X18878Y1487343D01*
G01Y1487096D02*
X18795Y1487014D01*
G01X16575Y1477835D02*
X17165Y1478425D01*
G01X15236Y1476496D02*
X14646Y1475906D01*
G01X16575Y1487835D02*
X17165Y1488425D01*
G01X15236Y1486496D02*
X14646Y1485906D01*
G01X19004Y1487137D02*
X18878Y1487096D01*
G01Y1487343D02*
X19004Y1487384D01*
G01X0Y1492165D02*
Y1613839D01*
G01Y1492165D02*
Y1613839D01*
G01X17520Y1611516D02*
G03X18110Y1610925I591J0D01*
G01X17520Y1616634D02*
G03X16929Y1617224I-591J-1D01*
G01X11220Y1621122D02*
G03X11417Y1620925I197J0D01*
G01Y1618957D02*
G03X11220Y1618760I0J-197D01*
G01Y1617421D02*
G03X11417Y1617224I197J0D01*
G01X-2953Y1626043D02*
G03Y1613839I0J-6102D01*
G01X11417Y1620925D02*
X30315D01*
G01Y1618957D02*
X11417D01*
G01Y1617224D02*
X16929D01*
G01X5906Y1613839D02*
X11220D01*
G01X5906D02*
X-2953D01*
G01X11220Y1613799D02*
X5906D01*
G01X27559Y1613773D02*
X11220D01*
G01X18110Y1610925D02*
X30315D01*
G01Y1609508D02*
X9843D01*
G01X30315Y1608957D02*
X14055D01*
G01X5906Y1608760D02*
X30315D01*
G01X28740Y1608366D02*
X30315D01*
G01X5906Y1606752D02*
X32677D01*
G01X30315Y1611988D02*
X28740Y1613878D01*
G01X14055Y1608957D02*
X11220Y1615471D01*
G01X28740Y1608366D02*
Y1631516D01*
G01X27559Y1626953D02*
Y1613773D01*
G01X17520Y1616634D02*
Y1611516D01*
G01X11417Y1617224D02*
Y1615018D01*
G01Y1620925D02*
Y1618957D01*
G01X11220Y1627971D02*
Y1613773D01*
G01Y1627421D02*
Y1613839D01*
G01X9843Y1630374D02*
Y1609508D01*
G01X7283Y1627421D02*
Y1613839D01*
G01X6496Y1626831D02*
Y1613839D01*
G01X5906Y1606752D02*
Y1633130D01*
G01X0Y1613839D02*
Y1626043D01*
G01Y1613839D02*
Y1626043D01*
G01X-2953Y1613839D02*
Y1626043D01*
G01X-5906Y1625272D02*
Y1614610D01*
G01X28740Y1614823D02*
X30315Y1617657D01*
G01X0Y1613839D02*
Y1626043D01*
G01Y1613839D02*
Y1626043D01*
G01Y1613839D02*
Y1626043D01*
G01Y1613839D02*
Y1626043D01*
G01X17879Y1628957D02*
G03X17289Y1628366I1J-591D01*
G01X11417Y1622657D02*
G03X11220Y1622461I0J-197D01*
G01X5906Y1633130D02*
X32677D01*
G01X28740Y1631516D02*
X30315D01*
G01X5906Y1631122D02*
X30315D01*
G01Y1630925D02*
X14134D01*
G01X30315Y1630374D02*
X9843D01*
G01X17879Y1628957D02*
X30315D01*
G01X11220Y1627971D02*
X5906D01*
G01X7283Y1627421D02*
X11220D01*
G01X27559Y1626953D02*
X11220D01*
G01X6496Y1626831D02*
X7283D01*
G01X5906Y1626043D02*
X-2953D01*
G01X6496D02*
X5906D01*
G01X17289Y1625020D02*
X16501D01*
G01X13189Y1622657D02*
X11417D01*
G01X30315Y1622224D02*
X28740Y1625059D01*
G01X17289Y1628366D02*
Y1625020D01*
G01X0Y1626043D02*
Y1741535D01*
G01X11220Y1624232D02*
X14134Y1630925D01*
G01X28740Y1626398D02*
X30315Y1627972D01*
G01X16501Y1625020D02*
X13189Y1622657D01*
G01X0Y1626043D02*
Y1741535D01*
G01Y1626043D02*
Y1741535D01*
G01Y1659055D02*
G03X-7874I-3937J0D01*
G01X0D02*
G03X-7874I-3937J0D01*
G01Y1689764D02*
G03X0I3937J0D01*
G01X-7874D02*
G03X0I3937J0D01*
G01X17879Y1756654D02*
G03X17289Y1756063I1J-591D01*
G01X17520Y1739213D02*
G03X18110Y1738622I590J-1D01*
G01X17520Y1744331D02*
G03X16929Y1744921I-591J-1D01*
G01X11417Y1750354D02*
G03X11220Y1750157I0J-197D01*
G01Y1748819D02*
G03X11417Y1748622I197J0D01*
G01Y1746654D02*
G03X11220Y1746457I0J-197D01*
G01Y1745118D02*
G03X11417Y1744921I197J0D01*
G01X-2953Y1753740D02*
G03Y1741535I0J-6103D01*
G01X5906Y1760827D02*
X32677D01*
G01X28740Y1759213D02*
X30315D01*
G01X5906Y1758819D02*
X30315D01*
G01Y1758622D02*
X14134D01*
G01X30315Y1758071D02*
X9843D01*
G01X17879Y1756654D02*
X30315D01*
G01X11220Y1755668D02*
X5906D01*
G01X7283Y1755118D02*
X11220D01*
G01X27559Y1754650D02*
X11220D01*
G01X6496Y1754528D02*
X7283D01*
G01X5906Y1753740D02*
X-2953D01*
G01X6496D02*
X5906D01*
G01X17289Y1752717D02*
X16501D01*
G01X13189Y1750354D02*
X11417D01*
G01Y1748622D02*
X30315D01*
G01Y1746654D02*
X11417D01*
G01Y1744921D02*
X16929D01*
G01X5906Y1741535D02*
X11220D01*
G01X5906D02*
X-2953D01*
G01X11220Y1741496D02*
X5906D01*
G01X27559Y1741470D02*
X11220D01*
G01X18110Y1738622D02*
X30315D01*
G01Y1737205D02*
X9843D01*
G01X30315Y1736654D02*
X14055D01*
G01X5906Y1736457D02*
X30315D01*
G01X28740Y1736063D02*
X30315D01*
G01X5906Y1734449D02*
X32677D01*
G01X30315Y1739685D02*
X28740Y1741575D01*
G01X30315Y1749921D02*
X28740Y1752756D01*
G01X14055Y1736654D02*
X11220Y1743167D01*
G01X28740Y1736063D02*
Y1759213D01*
G01X27559Y1754650D02*
Y1741470D01*
G01X17520Y1744331D02*
Y1739213D01*
G01X17289Y1756063D02*
Y1752717D01*
G01X11417Y1744921D02*
Y1742715D01*
G01Y1748622D02*
Y1746654D01*
G01X11220Y1755118D02*
Y1741535D01*
G01Y1755668D02*
Y1741470D01*
G01X9843Y1758071D02*
Y1737205D01*
G01X7283Y1755118D02*
Y1741535D01*
G01X6496Y1754528D02*
Y1741535D01*
G01X5906Y1734449D02*
Y1760827D01*
G01X0Y1753740D02*
Y1875394D01*
G01Y1741535D02*
Y1753740D01*
G01Y1741535D02*
Y1753740D01*
G01X-2953Y1741535D02*
Y1753740D01*
G01X-5906Y1752968D02*
Y1742307D01*
G01X11220Y1751929D02*
X14134Y1758622D01*
G01X28740Y1742520D02*
X30315Y1745354D01*
G01X28740Y1754094D02*
X30315Y1755669D01*
G01X16501Y1752717D02*
X13189Y1750354D01*
G01X0Y1753740D02*
Y1875394D01*
G01Y1753740D02*
Y1875394D01*
G01Y1741535D02*
Y1753740D01*
G01Y1741535D02*
Y1753740D01*
G01Y1741535D02*
Y1753740D01*
G01Y1741535D02*
Y1753740D01*
G01X34449Y1811024D02*
G03I-6890J0D01*
G01X37008Y1857087D02*
G03I-7087J0D01*
G01X0Y1876969D02*
X10000D01*
G01X0Y1876181D02*
X10000D01*
G01X0Y1875394D02*
X10000D01*
G01D02*
Y1925394D01*
G01X8819D02*
Y1875394D01*
G01X0D02*
Y1925394D01*
G01Y1875394D02*
Y1925394D01*
G01Y1875394D02*
Y1925394D01*
G01Y1875394D02*
Y1925394D01*
G01Y1875394D02*
Y1925394D01*
G01Y1875394D02*
Y1925394D01*
G01X13907Y1881654D02*
G03Y1879134I1998J-1260D01*
G01Y1891654D02*
G03Y1889134I1998J-1260D01*
G01Y1901654D02*
G03Y1899134I1998J-1260D01*
G01Y1911654D02*
G03Y1909134I1998J-1260D01*
G01Y1921654D02*
G03Y1919134I1998J-1260D01*
G01X0Y1925394D02*
X10000D01*
G01Y1924606D02*
X0D01*
G01X10000Y1923819D02*
X0D01*
G01X10000Y1921654D02*
X8819D01*
G01X17165D02*
X10000D01*
G01X18543Y1921432D02*
X20512D01*
G01Y1921186D02*
X18878D01*
G01X16575Y1921063D02*
X15236D01*
G01X19172Y1920940D02*
X18836D01*
G01X19004Y1920612D02*
X19172D01*
G01X19130Y1920366D02*
X19004D01*
G01X15236Y1919724D02*
X16575D01*
G01X18753Y1919341D02*
X19381D01*
G01X19632D02*
X20512D01*
G01X10000Y1919134D02*
X8819D01*
G01X17165D02*
X10000D01*
G01X20512Y1919094D02*
X18543D01*
G01X0Y1916969D02*
X10000D01*
G01X0Y1916181D02*
X10000D01*
G01Y1914606D02*
X0D01*
G01X10000Y1913819D02*
X0D01*
G01X10000Y1911654D02*
X8819D01*
G01X17165D02*
X10000D01*
G01X16575Y1911063D02*
X15236D01*
G01Y1909724D02*
X16575D01*
G01X10000Y1909134D02*
X8819D01*
G01X17165D02*
X10000D01*
G01X0Y1906969D02*
X10000D01*
G01X0Y1906181D02*
X10000D01*
G01Y1904606D02*
X0D01*
G01X10000Y1903819D02*
X0D01*
G01X10000Y1901654D02*
X8819D01*
G01X17165D02*
X10000D01*
G01X16575Y1901063D02*
X15236D01*
G01Y1899724D02*
X16575D01*
G01X10000Y1899134D02*
X8819D01*
G01X17165D02*
X10000D01*
G01X0Y1896969D02*
X10000D01*
G01X0Y1896181D02*
X10000D01*
G01Y1894606D02*
X0D01*
G01X10000Y1893819D02*
X0D01*
G01X10000Y1891654D02*
X8819D01*
G01X17165D02*
X10000D01*
G01X16575Y1891063D02*
X15236D01*
G01Y1889724D02*
X16575D01*
G01X10000Y1889134D02*
X8819D01*
G01X17165D02*
X10000D01*
G01X0Y1886969D02*
X10000D01*
G01X0Y1886181D02*
X10000D01*
G01Y1884606D02*
X0D01*
G01X10000Y1883819D02*
X0D01*
G01X10000Y1881654D02*
X8819D01*
G01X17165D02*
X10000D01*
G01X16575Y1881063D02*
X15236D01*
G01Y1879724D02*
X16575D01*
G01X10000Y1879134D02*
X8819D01*
G01X17165D02*
X10000D01*
G01X19172Y1920612D02*
X19297Y1920571D01*
G01X19255Y1920325D02*
X19130Y1920366D01*
G01X18878Y1921186D02*
X19172Y1920940D01*
G01X18836D02*
X18543Y1921186D01*
G01X19297Y1920571D02*
X19465Y1920448D01*
G01X15236Y1921063D02*
X14646Y1921654D01*
G01X17165Y1919134D02*
X16575Y1919724D01*
G01X19339Y1920243D02*
X19255Y1920325D01*
G01X15236Y1911063D02*
X14646Y1911654D01*
G01X17165Y1909134D02*
X16575Y1909724D01*
G01X15236Y1901063D02*
X14646Y1901654D01*
G01X17165Y1899134D02*
X16575Y1899724D01*
G01X15236Y1891063D02*
X14646Y1891654D01*
G01X17165Y1889134D02*
X16575Y1889724D01*
G01X17165Y1879134D02*
X16575Y1879724D01*
G01X15236Y1881063D02*
X14646Y1881654D01*
G01X19465Y1920448D02*
X19590Y1920284D01*
G01X19381Y1920120D02*
X19339Y1920243D01*
G01X19590Y1920284D02*
X19632Y1920079D01*
G01X20512Y1921432D02*
Y1921186D01*
G01Y1919341D02*
Y1919094D01*
G01X19632Y1920079D02*
Y1919341D01*
G01X19381D02*
Y1920120D01*
G01X18753D02*
Y1919341D01*
G01X18543Y1921186D02*
Y1921432D01*
G01Y1919094D02*
Y1920079D01*
G01X17165Y1881654D02*
Y1879134D01*
G01Y1891654D02*
Y1889134D01*
G01Y1901654D02*
Y1899134D01*
G01Y1911654D02*
Y1909134D01*
G01Y1921654D02*
Y1919134D01*
G01X16575Y1919724D02*
Y1921063D01*
G01Y1909724D02*
Y1911063D01*
G01Y1899724D02*
Y1901063D01*
G01Y1889724D02*
Y1891063D01*
G01Y1879724D02*
Y1881063D01*
G01X15236Y1919724D02*
Y1921063D01*
G01Y1909724D02*
Y1911063D01*
G01Y1899724D02*
Y1901063D01*
G01Y1889724D02*
Y1891063D01*
G01Y1879724D02*
Y1881063D01*
G01X14646Y1881654D02*
Y1879134D01*
G01Y1891654D02*
Y1889134D01*
G01Y1901654D02*
Y1899134D01*
G01Y1911654D02*
Y1909134D01*
G01Y1921654D02*
Y1919134D01*
G01X13661Y1881654D02*
Y1879134D01*
G01Y1891654D02*
Y1889134D01*
G01Y1901654D02*
Y1899134D01*
G01Y1911654D02*
Y1909134D01*
G01Y1921654D02*
Y1919134D01*
G01X0Y1925394D02*
Y1964567D01*
G01X18543Y1920079D02*
X18585Y1920284D01*
G01X18795Y1920243D02*
X18753Y1920120D01*
G01X18585Y1920284D02*
X18711Y1920448D01*
G01X16575Y1881063D02*
X17165Y1881654D01*
G01X15236Y1879724D02*
X14646Y1879134D01*
G01X16575Y1891063D02*
X17165Y1891654D01*
G01X15236Y1889724D02*
X14646Y1889134D01*
G01X16575Y1901063D02*
X17165Y1901654D01*
G01X15236Y1899724D02*
X14646Y1899134D01*
G01X16575Y1911063D02*
X17165Y1911654D01*
G01X15236Y1909724D02*
X14646Y1909134D01*
G01X16575Y1921063D02*
X17165Y1921654D01*
G01X15236Y1919724D02*
X14646Y1919134D01*
G01X18878Y1920325D02*
X18795Y1920243D01*
G01X18711Y1920448D02*
X18878Y1920571D01*
G01X19004Y1920366D02*
X18878Y1920325D01*
G01Y1920571D02*
X19004Y1920612D01*
G01X0Y1925394D02*
Y1964567D01*
G01Y1925394D02*
Y1964567D01*
G01Y1925984D02*
G03X-7874I-3937J0D01*
G01X0D02*
G03X-7874I-3937J0D01*
G01X37008Y1943701D02*
G03I-7087J0D01*
G01X3937Y1968504D02*
G03X0Y1964567I0J-3937D01*
G01X3937Y1968504D02*
X64961D01*
G01X-7874Y1964813D02*
Y2005727D01*
G01X0Y1964813D02*
Y1980315D01*
G01X3937Y1968504D02*
G03X0Y1964567I0J-3937D01*
G01X3937Y1968504D02*
G03X0Y1964567I0J-3937D01*
G01X3937Y1968504D02*
X64961D01*
G01X3937D02*
X64961D01*
G01X-7874Y1956693D02*
G03X0I3937J0D01*
G01X-7874D02*
G03X0I3937J0D01*
G01X-7874Y1964567D02*
G03X-11811Y1968504I-3937J0D01*
G01X-7874Y1964567D02*
G03X-11811Y1968504I-3937J0D01*
G01X3937D02*
G03X0Y1964567I0J-3937D01*
G01X3937Y1968504D02*
G03X0Y1964567I0J-3937D01*
G01X3937Y1968504D02*
X64961D01*
G01X3937D02*
X64961D01*
G01X3937D02*
G03X0Y1964567I0J-3937D01*
G01X64961Y1968504D02*
X3937D01*
G01X-7874Y1964567D02*
G03X-11811Y1968504I-3937J0D01*
G01X3937D02*
G03X0Y1964567I0J-3937D01*
G01X64961Y1968504D02*
X3937D01*
G01X-7874Y1964567D02*
G03X-11811Y1968504I-3937J0D01*
G01X6511Y2008727D02*
X5627Y2009390D01*
X5122Y2009958D01*
X4870Y2010716D01*
X5122Y2011379D01*
X5627Y2011852D01*
X6385Y2012231D01*
X7268Y2012326D01*
X8026Y2012231D01*
X8783Y2011852D01*
X9415Y2011284D01*
X9667Y2010621D01*
X9415Y2009864D01*
X8657Y2009201D01*
X7521Y2008822D01*
X6258Y2008727D01*
X4617Y2008917D01*
X3733Y2009201D01*
X2850Y2009674D01*
X2218Y2010337D01*
X2092Y2011000D01*
X2344Y2011663D01*
X2976Y2012136D01*
G01X9667Y2018101D02*
X2092D01*
X3607Y2016965D01*
G01X9667D02*
Y2019238D01*
G01X9919Y2025676D02*
X9793Y2025487D01*
X9541D01*
X9415Y2025676D01*
X9541Y2025866D01*
X9793D01*
X9919Y2025676D01*
G01X8531Y2031168D02*
X9162Y2031736D01*
X9541Y2032399D01*
X9667Y2033251D01*
X9415Y2034104D01*
X8910Y2034766D01*
X8026Y2035240D01*
X7016Y2035335D01*
X6006Y2035145D01*
X5374Y2034672D01*
X4870Y2034009D01*
X4743Y2033346D01*
X4870Y2032683D01*
X5374Y2031831D01*
X2092Y2032115D01*
Y2034672D01*
G01Y2040826D02*
X2344Y2040069D01*
X2976Y2039501D01*
X3733Y2039122D01*
X4743Y2038838D01*
X5880Y2038743D01*
X7016Y2038838D01*
X8026Y2039122D01*
X8783Y2039501D01*
X9415Y2040069D01*
X9667Y2040826D01*
X9415Y2041584D01*
X8783Y2042152D01*
X8026Y2042531D01*
X7016Y2042815D01*
X5880Y2042910D01*
X4743Y2042815D01*
X3733Y2042531D01*
X2976Y2042152D01*
X2344Y2041584D01*
X2092Y2040826D01*
G01X-5073Y2006838D02*
X-4442Y2007406D01*
X-4063Y2008069D01*
X-3937Y2008921D01*
X-4189Y2009774D01*
X-4694Y2010436D01*
X-5578Y2010910D01*
X-6588Y2011005D01*
X-7598Y2010815D01*
X-8230Y2010342D01*
X-8734Y2009679D01*
X-8861Y2009016D01*
X-8734Y2008353D01*
X-8230Y2007501D01*
X-11512Y2007785D01*
Y2010342D01*
G01X-4821Y2014887D02*
X-4189Y2015550D01*
X-3937Y2016307D01*
X-4189Y2017065D01*
X-4947Y2017727D01*
X-6083Y2018201D01*
X-7219Y2018390D01*
X-8608D01*
X-9744Y2018201D01*
X-10754Y2017727D01*
X-11260Y2017159D01*
X-11512Y2016496D01*
X-11260Y2015739D01*
X-10754Y2015171D01*
X-9997Y2014792D01*
X-8987Y2014603D01*
X-8103Y2014792D01*
X-7219Y2015266D01*
X-6714Y2015834D01*
X-6588Y2016496D01*
X-6841Y2017254D01*
X-7472Y2017822D01*
X-8608Y2018390D01*
G01X-3685Y2024071D02*
X-3811Y2023882D01*
X-4063D01*
X-4189Y2024071D01*
X-4063Y2024261D01*
X-3811D01*
X-3685Y2024071D01*
G01X-5073Y2029563D02*
X-4442Y2030131D01*
X-4063Y2030794D01*
X-3937Y2031646D01*
X-4189Y2032499D01*
X-4694Y2033161D01*
X-5578Y2033635D01*
X-6588Y2033730D01*
X-7598Y2033540D01*
X-8230Y2033067D01*
X-8734Y2032404D01*
X-8861Y2031741D01*
X-8734Y2031078D01*
X-8230Y2030226D01*
X-11512Y2030510D01*
Y2033067D01*
G01Y2039221D02*
X-11260Y2038464D01*
X-10628Y2037896D01*
X-9871Y2037517D01*
X-8861Y2037233D01*
X-7724Y2037138D01*
X-6588Y2037233D01*
X-5578Y2037517D01*
X-4821Y2037896D01*
X-4189Y2038464D01*
X-3937Y2039221D01*
X-4189Y2039979D01*
X-4821Y2040547D01*
X-5578Y2040926D01*
X-6588Y2041210D01*
X-7724Y2041305D01*
X-8861Y2041210D01*
X-9871Y2040926D01*
X-10628Y2040547D01*
X-11260Y2039979D01*
X-11512Y2039221D01*
G01X5730Y1991584D02*
Y2007332D01*
G01X0Y1980315D02*
X5730Y1991584D01*
G01X18947Y2099793D02*
X19799Y2098468D01*
X20936Y2097710D01*
X22214Y2097521D01*
X23350Y2097710D01*
X24487Y2098657D01*
X25197Y2099793D01*
X25339Y2100930D01*
X25055Y2102255D01*
X24060Y2103202D01*
X23066Y2103581D01*
X21788D01*
G01X23066D02*
X23918Y2104149D01*
X24629Y2105095D01*
X24913Y2106232D01*
X24629Y2107368D01*
X23918Y2108315D01*
X22640Y2108883D01*
X21362Y2108694D01*
X20084Y2107936D01*
G01X72835Y39370D02*
G03X68898Y35433I0J-3937D01*
G01X64961Y0D02*
G03X68898Y3937I0J3937D01*
G01Y35433D02*
Y3937D01*
G01X72835Y39370D02*
G03X68898Y35433I0J-3937D01*
G01X72835Y39370D02*
G03X68898Y35433I0J-3937D01*
G01X64961Y0D02*
G03X68898Y3937I0J3937D01*
G01X64961Y0D02*
G03X68898Y3937I0J3937D01*
G01Y35433D02*
Y3937D01*
G01Y35433D02*
Y3937D01*
G01X168110Y31496D02*
X76763D01*
G01X72835Y39370D02*
G03X68898Y35433I0J-3937D01*
G01X72835Y39370D02*
G03X68898Y35433I0J-3937D01*
G01X64961Y0D02*
G03X68898Y3937I0J3937D01*
G01X64961Y0D02*
G03X68898Y3937I0J3937D01*
G01Y35433D02*
Y3937D01*
G01Y35433D02*
Y3937D01*
G01X72835Y39370D02*
G03X68898Y35433I0J-3937D01*
G01Y3937D02*
Y35485D01*
G01X64961Y0D02*
G03X68898Y3937I0J3937D01*
G01X76763D02*
G03X80700Y0I3937J0D01*
G01X76763Y7615D02*
Y3937D01*
G01D02*
Y7615D01*
G01X168110Y31496D02*
X76763D01*
G01Y7615D02*
G03X68889I-3937J0D01*
G01Y31496D02*
G03X76763I3937J0D01*
G01X72835Y39370D02*
G03X68898Y35433I0J-3937D01*
G01Y3937D02*
Y35485D01*
G01X64961Y0D02*
G03X68898Y3937I0J3937D01*
G01X76763D02*
G03X80700Y0I3937J0D01*
G01X76763Y7615D02*
Y3937D01*
G01D02*
Y7615D01*
G01X168110Y31496D02*
X76763D01*
G01Y7615D02*
G03X68889I-3937J0D01*
G01Y31496D02*
G03X76763I3937J0D01*
G01X52953Y68110D02*
G03I-5709J0D01*
G01X202756Y39370D02*
X72835D01*
G01X202756D02*
X72835D01*
G01X202756D02*
X72835D01*
G01X202756D02*
X72835D01*
G01X202756D02*
X72835D01*
G01D02*
X202756D01*
G01X72835D02*
X202756D01*
G01X85610Y139409D02*
G03I-4901J0D01*
G01X86809Y119409D02*
G03I-6100J0D01*
G01X86969D02*
G03I-6260J0D01*
G01X79359Y134459D02*
Y144359D01*
G01X67009Y109409D02*
Y339409D01*
G01X82059Y134459D02*
X79359D01*
G01X67009Y109409D02*
X94409D01*
G01X78979Y162910D02*
G03X82438I1730J-1020D01*
G01X78979Y182910D02*
G03X82438I1730J-1020D01*
G01X82461Y170909D02*
G03X78956I-1753J980D01*
G01X79459Y162909D02*
Y160909D01*
G01Y172909D02*
Y170909D01*
G01Y182909D02*
Y180909D01*
G01X78553D02*
Y182909D01*
G01Y170909D02*
Y172909D01*
G01Y160909D02*
Y162909D01*
G01X77939Y182909D02*
Y190909D01*
G01Y162909D02*
Y170909D01*
G01X72009Y154409D02*
Y199409D01*
G01X70009Y143409D02*
Y305409D01*
G01X77939Y182909D02*
X113339D01*
G01X78553Y180909D02*
X109414D01*
G01X78553Y172909D02*
X109414D01*
G01X77939Y170909D02*
X113339D01*
G01X77939Y162909D02*
X113339D01*
G01X78553Y160909D02*
X109414D01*
G01X70009Y154409D02*
X121409D01*
G01X79359Y144359D02*
X82059D01*
G01X86509Y143409D02*
X70009D01*
G01X67009Y139409D02*
X94409D01*
G01X82717Y224409D02*
G03I-2008J0D01*
G01Y234409D02*
G03I-2008J0D01*
G01Y204409D02*
G03I-2008J0D01*
G01Y214409D02*
G03I-2008J0D01*
G01X82461Y190909D02*
G03X78956I-1753J980D01*
G01X79068Y202769D02*
X79459Y203159D01*
G01X79068Y212769D02*
X79459Y213159D01*
G01X79068Y222769D02*
X79459Y223159D01*
G01X79068Y232769D02*
X79459Y233159D01*
G01X30709Y229291D02*
X30315Y228898D01*
G01X30709Y219291D02*
X30315Y218583D01*
G01X79459Y233159D02*
Y235659D01*
G01Y223159D02*
Y225659D01*
G01Y213159D02*
Y215659D01*
G01Y203159D02*
Y205659D01*
G01Y192909D02*
Y190909D01*
G01X79329Y233029D02*
Y235789D01*
G01Y223029D02*
Y225789D01*
G01Y213029D02*
Y215789D01*
G01Y203029D02*
Y205789D01*
G01X79068Y232769D02*
Y236050D01*
G01Y222769D02*
Y226050D01*
G01Y212769D02*
Y216050D01*
G01Y202769D02*
Y206050D01*
G01X78553Y190909D02*
Y192909D01*
G01X72209Y199409D02*
Y249409D01*
G01X32677Y231850D02*
Y234055D01*
G01Y221850D02*
Y229882D01*
G01Y211850D02*
Y219882D01*
G01Y207677D02*
Y209882D01*
G01Y211014D02*
Y210768D01*
G01X32283Y211850D02*
Y209882D01*
G01Y221850D02*
Y219882D01*
G01Y231850D02*
Y229882D01*
G01X31535Y211850D02*
Y209882D01*
G01Y221850D02*
Y219882D01*
G01Y231850D02*
Y229882D01*
G01X30709Y210768D02*
Y211014D01*
G01X30315Y228898D02*
Y232441D01*
G01Y218583D02*
Y223150D01*
G01Y219882D02*
Y221850D01*
G01Y209291D02*
Y212913D01*
G01Y211850D02*
Y209882D01*
G01Y231850D02*
Y229882D01*
G01Y223150D02*
X30709Y222441D01*
G01X30315Y212913D02*
X30709Y212441D01*
G01X79068Y236050D02*
X79459Y235659D01*
G01X79068Y226050D02*
X79459Y225659D01*
G01X79068Y216050D02*
X79459Y215659D01*
G01X79068Y206050D02*
X79459Y205659D01*
G01X32384Y211260D02*
X32677Y211014D01*
G01X32342D02*
X32283Y211063D01*
G01D02*
X32049Y211260D01*
G01X79068Y236050D02*
X82349D01*
G01X79329Y235789D02*
X82089D01*
G01X79459Y235659D02*
X81959D01*
G01Y233159D02*
X79459D01*
G01X82089Y233029D02*
X79329D01*
G01X82349Y232769D02*
X79068D01*
G01X32677Y232441D02*
X30315D01*
G01Y231850D02*
X32283D01*
G01X32677D02*
X32283D01*
G01D02*
X30315D01*
G01Y229882D02*
X32283D01*
G01X32677D02*
X32283D01*
G01D02*
X30315D01*
G01X32677Y229291D02*
X30709D01*
G01X79068Y226050D02*
X82349D01*
G01X79329Y225789D02*
X82089D01*
G01X79459Y225659D02*
X81959D01*
G01Y223159D02*
X79459D01*
G01X82089Y223029D02*
X79329D01*
G01X82349Y222769D02*
X79068D01*
G01X32677Y222441D02*
X30709D01*
G01X30315Y221850D02*
X32283D01*
G01X32677D02*
X32283D01*
G01D02*
X30315D01*
G01X32283Y219882D02*
X30315D01*
G01X32677D02*
X32283D01*
G01D02*
X30315D01*
G01X32677Y219291D02*
X30709D01*
G01X79068Y216050D02*
X82349D01*
G01X79329Y215789D02*
X82089D01*
G01X79459Y215659D02*
X81959D01*
G01Y213159D02*
X79459D01*
G01X82089Y213029D02*
X79329D01*
G01X82349Y212769D02*
X79068D01*
G01X32677Y212441D02*
X30709D01*
G01X30315Y211850D02*
X32283D01*
G01X32677D02*
X32283D01*
G01D02*
X30315D01*
G01X32283Y211260D02*
X32384D01*
G01X32049D02*
X32283D01*
G01Y211014D02*
X32342D01*
G01X30709D02*
X32283D01*
G01X32677Y210768D02*
X32283D01*
G01D02*
X30709D01*
G01X32283Y209882D02*
X30315D01*
G01X32677D02*
X32283D01*
G01D02*
X30315D01*
G01X32677Y209291D02*
X30315D01*
G01X79068Y206050D02*
X82349D01*
G01X79329Y205789D02*
X82089D01*
G01X79459Y205659D02*
X81959D01*
G01Y203159D02*
X79459D01*
G01X82089Y203029D02*
X79329D01*
G01X82349Y202769D02*
X79068D01*
G01X70013Y199409D02*
X72209D01*
G01X78553Y192909D02*
X109414D01*
G01X77939Y190909D02*
X113339D01*
G01X78956Y277910D02*
G03X82461I1753J-981D01*
G01X82438Y285909D02*
G03X78979I-1729J1020D01*
G01X82717Y244409D02*
G03I-2008J0D01*
G01X78956Y257910D02*
G03X82461I1753J-981D01*
G01X82438Y265909D02*
G03X78979I-1729J1020D01*
G01X79068Y242769D02*
X79459Y243159D01*
G01D02*
Y245659D01*
G01Y257909D02*
Y255909D01*
G01Y267909D02*
Y265909D01*
G01Y277909D02*
Y275909D01*
G01Y287909D02*
Y285909D01*
G01X79329Y243029D02*
Y245789D01*
G01X79068Y242769D02*
Y246050D01*
G01X78553Y285909D02*
Y287909D01*
G01Y275909D02*
Y277909D01*
G01Y265909D02*
Y267909D01*
G01Y255909D02*
Y257909D01*
G01X77939Y277909D02*
Y285909D01*
G01Y257909D02*
Y265909D01*
G01X72009Y249409D02*
Y294409D01*
G01X79068Y246050D02*
X79459Y245659D01*
G01X78553Y287909D02*
X109414D01*
G01X77939Y285909D02*
X113339D01*
G01X77939Y277909D02*
X113339D01*
G01X78553Y275909D02*
X109414D01*
G01X78553Y267909D02*
X109414D01*
G01X77939Y265909D02*
X113339D01*
G01X77939Y257909D02*
X113339D01*
G01X78553Y255909D02*
X109414D01*
G01X70013Y249409D02*
X72209D01*
G01X79068Y246050D02*
X82349D01*
G01X79329Y245789D02*
X82089D01*
G01X79459Y245659D02*
X81959D01*
G01Y243159D02*
X79459D01*
G01X82089Y243029D02*
X79329D01*
G01X82349Y242769D02*
X79068D01*
G01X85610Y309409D02*
G03I-4901J0D01*
G01X86809Y329409D02*
G03I-6100J0D01*
G01X86969D02*
G03I-6260J0D01*
G01X79359Y304459D02*
Y314359D01*
G01X32677Y339547D02*
Y347579D01*
G01Y335374D02*
Y337579D01*
G01Y338711D02*
Y338465D01*
G01X32283Y339547D02*
Y337579D01*
G01X31535Y339547D02*
Y337579D01*
G01X30709Y338465D02*
Y338711D01*
G01X30315Y336988D02*
Y340610D01*
G01Y339547D02*
Y337579D01*
G01Y340610D02*
X30709Y340138D01*
G01X32384Y338957D02*
X32677Y338711D01*
G01X32342D02*
X32283Y338760D01*
G01D02*
X32049Y338957D01*
G01X32677Y340138D02*
X30709D01*
G01X30315Y339547D02*
X32283D01*
G01X32677D02*
X32283D01*
G01D02*
X30315D01*
G01X94409Y339409D02*
X67009D01*
G01X32283Y338957D02*
X32384D01*
G01X32049D02*
X32283D01*
G01Y338711D02*
X32342D01*
G01X30709D02*
X32283D01*
G01X32677Y338465D02*
X32283D01*
G01D02*
X30709D01*
G01X32283Y337579D02*
X30315D01*
G01X32677D02*
X32283D01*
G01D02*
X30315D01*
G01X32677Y336988D02*
X30315D01*
G01X79359Y314359D02*
X82059D01*
G01X94409Y309409D02*
X67009D01*
G01X70009Y305409D02*
X86509D01*
G01X82059Y304459D02*
X79359D01*
G01X70009Y294409D02*
X121409D01*
G01X30709Y356988D02*
X30315Y356594D01*
G01X30709Y346988D02*
X30315Y346280D01*
G01X32677Y359547D02*
Y361752D01*
G01Y349547D02*
Y357579D01*
G01X32283Y349547D02*
Y347579D01*
G01Y359547D02*
Y357579D01*
G01X31535Y349547D02*
Y347579D01*
G01Y359547D02*
Y357579D01*
G01X30315Y356594D02*
Y360138D01*
G01Y346280D02*
Y350846D01*
G01Y347579D02*
Y349547D01*
G01Y359547D02*
Y357579D01*
G01Y350846D02*
X30709Y350138D01*
G01X32677Y360138D02*
X30315D01*
G01Y359547D02*
X32283D01*
G01X32677D02*
X32283D01*
G01D02*
X30315D01*
G01Y357579D02*
X32283D01*
G01X32677D02*
X32283D01*
G01D02*
X30315D01*
G01X32677Y356988D02*
X30709D01*
G01X32677Y350138D02*
X30709D01*
G01X30315Y349547D02*
X32283D01*
G01X32677D02*
X32283D01*
G01D02*
X30315D01*
G01X32283Y347579D02*
X30315D01*
G01X32677D02*
X32283D01*
G01D02*
X30315D01*
G01X32677Y346988D02*
X30709D01*
G01X52953Y501339D02*
G03I-5709J0D01*
G01Y761181D02*
G03I-5709J0D01*
G01X30315Y905965D02*
X30709Y905492D01*
G01X32384Y904311D02*
X32677Y904065D01*
G01X32342D02*
X32283Y904114D01*
G01D02*
X32049Y904311D01*
G01X32677Y905492D02*
X30709D01*
G01X30315Y904902D02*
X32283D01*
G01X32677D02*
X32283D01*
G01D02*
X30315D01*
G01X32283Y904311D02*
X32384D01*
G01X32049D02*
X32283D01*
G01Y904065D02*
X32342D01*
G01X30709D02*
X32283D01*
G01X32677Y903819D02*
X32283D01*
G01D02*
X30709D01*
G01X32283Y902933D02*
X30315D01*
G01X32677D02*
X32283D01*
G01D02*
X30315D01*
G01X32677Y902343D02*
X30315D01*
G01X32677Y904902D02*
Y912933D01*
G01Y900728D02*
Y902933D01*
G01Y904065D02*
Y903819D01*
G01X32283Y904902D02*
Y902933D01*
G01X31535Y904902D02*
Y902933D01*
G01X30709Y903819D02*
Y904065D01*
G01X30315Y902343D02*
Y905965D01*
G01Y904902D02*
Y902933D01*
G01X30709Y922343D02*
X30315Y921949D01*
G01X30709Y912343D02*
X30315Y911634D01*
G01Y916201D02*
X30709Y915492D01*
G01X32677Y925492D02*
X30315D01*
G01Y924902D02*
X32283D01*
G01X32677D02*
X32283D01*
G01D02*
X30315D01*
G01Y922933D02*
X32283D01*
G01X32677D02*
X32283D01*
G01D02*
X30315D01*
G01X32677Y922343D02*
X30709D01*
G01X32677Y915492D02*
X30709D01*
G01X30315Y914902D02*
X32283D01*
G01X32677D02*
X32283D01*
G01D02*
X30315D01*
G01X32283Y912933D02*
X30315D01*
G01X32677D02*
X32283D01*
G01D02*
X30315D01*
G01X32677Y912343D02*
X30709D01*
G01X32677Y924902D02*
Y927106D01*
G01Y914902D02*
Y922933D01*
G01X32283Y914902D02*
Y912933D01*
G01Y924902D02*
Y922933D01*
G01X31535Y914902D02*
Y912933D01*
G01Y924902D02*
Y922933D01*
G01X30315Y921949D02*
Y925492D01*
G01Y911634D02*
Y916201D01*
G01Y912933D02*
Y914902D01*
G01Y924902D02*
Y922933D01*
G01X32677Y1056161D02*
X30709D01*
G01X30315Y1055571D02*
X32283D01*
G01X32677D02*
X32283D01*
G01D02*
X30315D01*
G01X32283Y1053602D02*
X30315D01*
G01X32677D02*
X32283D01*
G01D02*
X30315D01*
G01X32677Y1053012D02*
X30709D01*
G01X32677Y1046161D02*
X30709D01*
G01X30315Y1045571D02*
X32283D01*
G01X32677D02*
X32283D01*
G01D02*
X30315D01*
G01X32283Y1044980D02*
X32384D01*
G01X32049D02*
X32283D01*
G01Y1044734D02*
X32342D01*
G01X30709D02*
X32283D01*
G01X32677Y1044488D02*
X32283D01*
G01D02*
X30709D01*
G01X32283Y1043602D02*
X30315D01*
G01X32677D02*
X32283D01*
G01D02*
X30315D01*
G01X32677Y1043012D02*
X30315D01*
G01Y1056870D02*
X30709Y1056161D01*
G01X30315Y1046634D02*
X30709Y1046161D01*
G01X32384Y1044980D02*
X32677Y1044734D01*
G01X32342D02*
X32283Y1044783D01*
G01D02*
X32049Y1044980D01*
G01X30709Y1053012D02*
X30315Y1052303D01*
G01X32677Y1055571D02*
Y1063602D01*
G01Y1045571D02*
Y1053602D01*
G01Y1041398D02*
Y1043602D01*
G01Y1044734D02*
Y1044488D01*
G01X32283Y1045571D02*
Y1043602D01*
G01Y1055571D02*
Y1053602D01*
G01X31535Y1045571D02*
Y1043602D01*
G01Y1055571D02*
Y1053602D01*
G01X30709Y1044488D02*
Y1044734D01*
G01X30315Y1052303D02*
Y1056870D01*
G01Y1053602D02*
Y1055571D01*
G01Y1043012D02*
Y1046634D01*
G01Y1045571D02*
Y1043602D01*
G01X32677Y1066161D02*
X30315D01*
G01Y1065571D02*
X32283D01*
G01X32677D02*
X32283D01*
G01D02*
X30315D01*
G01Y1063602D02*
X32283D01*
G01X32677D02*
X32283D01*
G01D02*
X30315D01*
G01X32677Y1063012D02*
X30709D01*
G01D02*
X30315Y1062618D01*
G01X32677Y1065571D02*
Y1067776D01*
G01X32283Y1065571D02*
Y1063602D01*
G01X31535Y1065571D02*
Y1063602D01*
G01X30315Y1062618D02*
Y1066161D01*
G01Y1065571D02*
Y1063602D01*
G01X52953Y1207323D02*
G03I-5709J0D01*
G01Y1467165D02*
G03I-5709J0D01*
G01X32677Y1621516D02*
X30709D01*
G01X30315Y1620925D02*
X32283D01*
G01X32677D02*
X32283D01*
G01D02*
X30315D01*
G01X32283Y1618957D02*
X30315D01*
G01X32677D02*
X32283D01*
G01D02*
X30315D01*
G01X32677Y1618366D02*
X30709D01*
G01X32677Y1611516D02*
X30709D01*
G01X30315Y1610925D02*
X32283D01*
G01X32677D02*
X32283D01*
G01D02*
X30315D01*
G01X32283Y1610335D02*
X32384D01*
G01X32049D02*
X32283D01*
G01Y1610089D02*
X32342D01*
G01X30709D02*
X32283D01*
G01X32677Y1609843D02*
X32283D01*
G01D02*
X30709D01*
G01X32283Y1608957D02*
X30315D01*
G01X32677D02*
X32283D01*
G01D02*
X30315D01*
G01X32677Y1608366D02*
X30315D01*
G01X32384Y1610335D02*
X32677Y1610089D01*
G01X32342D02*
X32283Y1610138D01*
G01D02*
X32049Y1610335D01*
G01X30315Y1611988D02*
X30709Y1611516D01*
G01X30315Y1622224D02*
X30709Y1621516D01*
G01X32677Y1620925D02*
Y1628957D01*
G01Y1610925D02*
Y1618957D01*
G01Y1606752D02*
Y1608957D01*
G01Y1610089D02*
Y1609843D01*
G01X32283Y1610925D02*
Y1608957D01*
G01Y1620925D02*
Y1618957D01*
G01X31535Y1610925D02*
Y1608957D01*
G01Y1620925D02*
Y1618957D01*
G01X30709Y1609843D02*
Y1610089D01*
G01X30315Y1617657D02*
Y1622224D01*
G01Y1618957D02*
Y1620925D01*
G01Y1608366D02*
Y1611988D01*
G01Y1610925D02*
Y1608957D01*
G01X30709Y1618366D02*
X30315Y1617657D01*
G01X32677Y1631516D02*
X30315D01*
G01Y1630925D02*
X32283D01*
G01X32677D02*
X32283D01*
G01D02*
X30315D01*
G01Y1628957D02*
X32283D01*
G01X32677D02*
X32283D01*
G01D02*
X30315D01*
G01X32677Y1628366D02*
X30709D01*
G01X32677Y1630925D02*
Y1633130D01*
G01X32283Y1630925D02*
Y1628957D01*
G01X31535Y1630925D02*
Y1628957D01*
G01X30315Y1627972D02*
Y1631516D01*
G01Y1630925D02*
Y1628957D01*
G01X30709Y1628366D02*
X30315Y1627972D01*
G01X123424Y1689960D02*
X69487D01*
G01X123424D02*
X69487D01*
G01D02*
Y1856889D01*
G01Y1689960D02*
Y1856889D01*
G01X115156Y1747834D02*
G03I-18701J0D01*
G01X32677Y1759213D02*
X30315D01*
G01Y1758622D02*
X32283D01*
G01X32677D02*
X32283D01*
G01D02*
X30315D01*
G01Y1756654D02*
X32283D01*
G01X32677D02*
X32283D01*
G01D02*
X30315D01*
G01X32677Y1756063D02*
X30709D01*
G01X32677Y1749213D02*
X30709D01*
G01X30315Y1748622D02*
X32283D01*
G01X32677D02*
X32283D01*
G01D02*
X30315D01*
G01X32283Y1746654D02*
X30315D01*
G01X32677D02*
X32283D01*
G01D02*
X30315D01*
G01X32677Y1746063D02*
X30709D01*
G01X32677Y1739213D02*
X30709D01*
G01X30315Y1738622D02*
X32283D01*
G01X32677D02*
X32283D01*
G01D02*
X30315D01*
G01X32283Y1738032D02*
X32384D01*
G01X32049D02*
X32283D01*
G01Y1737785D02*
X32342D01*
G01X30709D02*
X32283D01*
G01X32677Y1737539D02*
X32283D01*
G01D02*
X30709D01*
G01X32283Y1736654D02*
X30315D01*
G01X32677D02*
X32283D01*
G01D02*
X30315D01*
G01X32677Y1736063D02*
X30315D01*
G01X32384Y1738032D02*
X32677Y1737785D01*
G01X32342D02*
X32283Y1737835D01*
G01D02*
X32049Y1738032D01*
G01X30315Y1739685D02*
X30709Y1739213D01*
G01X30315Y1749921D02*
X30709Y1749213D01*
G01X32677Y1758622D02*
Y1760827D01*
G01Y1748622D02*
Y1756654D01*
G01Y1738622D02*
Y1746654D01*
G01Y1734449D02*
Y1736654D01*
G01Y1737785D02*
Y1737539D01*
G01X32283Y1738622D02*
Y1736654D01*
G01Y1748622D02*
Y1746654D01*
G01Y1758622D02*
Y1756654D01*
G01X31535Y1738622D02*
Y1736654D01*
G01Y1748622D02*
Y1746654D01*
G01Y1758622D02*
Y1756654D01*
G01X30709Y1737539D02*
Y1737785D01*
G01X30315Y1755669D02*
Y1759213D01*
G01Y1745354D02*
Y1749921D01*
G01Y1746654D02*
Y1748622D01*
G01Y1736063D02*
Y1739685D01*
G01Y1738622D02*
Y1736654D01*
G01Y1758622D02*
Y1756654D01*
G01X30709Y1746063D02*
X30315Y1745354D01*
G01X30709Y1756063D02*
X30315Y1755669D01*
G01X115156Y1823031D02*
G03I-18701J0D01*
G01X69487Y1856889D02*
X123424D01*
G01X69487D02*
X123424D01*
G01X52953Y1900394D02*
G03I-5709J0D01*
G01X68898Y1933071D02*
G03X72835Y1929134I3937J0D01*
G01X68898Y1964567D02*
G03X64961Y1968504I-3937J0D01*
G01X72835Y1929134D02*
X202756D01*
G01X68898Y1964567D02*
Y1933071D01*
G01Y1964567D02*
G03X64961Y1968504I-3937J0D01*
G01X68898Y1933071D02*
G03X72835Y1929134I3937J0D01*
G01X68898Y1933071D02*
G03X72835Y1929134I3937J0D01*
G01X68898Y1964567D02*
G03X64961Y1968504I-3937J0D01*
G01X72835Y1929134D02*
X202756D01*
G01X72835D02*
X202756D01*
G01X68898Y1964567D02*
Y1933071D01*
G01Y1964567D02*
Y1933071D01*
G01Y1964567D02*
G03X64961Y1968504I-3937J0D01*
G01X68898Y1933071D02*
G03X72835Y1929134I3937J0D01*
G01X68898Y1933071D02*
G03X72835Y1929134I3937J0D01*
G01X68898Y1964567D02*
G03X64961Y1968504I-3937J0D01*
G01X72835Y1929134D02*
X202756D01*
G01X72835D02*
X202756D01*
G01X68898Y1964567D02*
Y1933071D01*
G01Y1964567D02*
Y1933071D01*
G01Y1964567D02*
G03X64961Y1968504I-3937J0D01*
G01X68898Y1933071D02*
Y1964567D01*
G01Y1933071D02*
G03X72835Y1929134I3937J0D01*
G01X202756D02*
X72835D01*
G01X80709Y1968504D02*
G03X76772Y1964567I0J-3937D01*
G01Y1960630D02*
Y1964567D01*
G01X168110Y1937008D02*
X76772D01*
G01X68898Y1960630D02*
G03X76772I3937J0D01*
G01Y1937008D02*
G03X68898I-3937J0D01*
G01Y1964567D02*
G03X64961Y1968504I-3937J0D01*
G01X68898Y1933071D02*
Y1964567D01*
G01Y1933071D02*
G03X72835Y1929134I3937J0D01*
G01X202756D02*
X72835D01*
G01X80709Y1968504D02*
G03X76772Y1964567I0J-3937D01*
G01Y1960630D02*
Y1964567D01*
G01X168110Y1937008D02*
X76772D01*
G01X68898Y1960630D02*
G03X76772I3937J0D01*
G01Y1937008D02*
G03X68898I-3937J0D01*
G01X131433Y-65085D02*
Y-84022D01*
G01X80700Y0D02*
X340551D01*
G01X80700D02*
X340551D01*
G01X124409Y137909D02*
Y310909D01*
G01X94409Y109409D02*
Y145409D01*
G01X82059Y144359D02*
Y134459D01*
G01X124409Y137909D02*
X94409D01*
G01X108979Y182910D02*
G03X112438I1730J-1020D01*
G01X108979Y162910D02*
G03X112438I1730J-1020D01*
G01X112461Y170909D02*
G03X108956I-1752J980D01*
G01X98979Y182910D02*
G03X102438I1730J-1020D01*
G01X98979Y162910D02*
G03X102438I1730J-1020D01*
G01X102461Y170909D02*
G03X98956I-1753J980D01*
G01X88979Y162910D02*
G03X92438I1730J-1020D01*
G01X88979Y182910D02*
G03X92438I1730J-1020D01*
G01X92461Y170909D02*
G03X88956I-1753J980D01*
G01X121409Y298409D02*
Y150409D01*
G01X119409Y154409D02*
Y199409D01*
G01X113339Y170909D02*
Y162909D01*
G01Y190909D02*
Y182909D01*
G01X111959Y180909D02*
Y182909D01*
G01Y170909D02*
Y172909D01*
G01Y160909D02*
Y162909D01*
G01X109459D02*
Y160909D01*
G01Y172909D02*
Y170909D01*
G01Y182909D02*
Y180909D01*
G01X109414Y162909D02*
Y160909D01*
G01Y172909D02*
Y170909D01*
G01Y182909D02*
Y180909D01*
G01X104622Y162909D02*
Y160909D01*
G01Y172909D02*
Y170909D01*
G01Y182909D02*
Y180909D01*
G01X101959D02*
Y182909D01*
G01Y170909D02*
Y172909D01*
G01Y160909D02*
Y162909D01*
G01X99459D02*
Y160909D01*
G01Y172909D02*
Y170909D01*
G01Y182909D02*
Y180909D01*
G01X94409Y145409D02*
Y145909D01*
G01X91959Y180909D02*
Y182909D01*
G01Y170909D02*
Y172909D01*
G01Y160909D02*
Y162909D01*
G01X89459D02*
Y160909D01*
G01Y172909D02*
Y170909D01*
G01Y182909D02*
Y180909D01*
G01X86509Y150409D02*
Y143409D01*
G01X83346Y162909D02*
Y160909D01*
G01Y172909D02*
Y170909D01*
G01Y182909D02*
Y180909D01*
G01X81959D02*
Y182909D01*
G01Y170909D02*
Y172909D01*
G01Y160909D02*
Y162909D01*
G01X109459Y180909D02*
X111959D01*
G01Y172909D02*
X109459D01*
G01Y160909D02*
X111959D01*
G01X121409Y150409D02*
X86509D01*
G01X94409Y145909D02*
X124409D01*
G01X94409Y145409D02*
X124409D01*
G01X112717Y204409D02*
G03I-2008J0D01*
G01Y214409D02*
G03I-2008J0D01*
G01Y224409D02*
G03I-2008J0D01*
G01Y234409D02*
G03I-2008J0D01*
G01X102717Y204409D02*
G03I-2008J0D01*
G01Y214409D02*
G03I-2008J0D01*
G01Y224409D02*
G03I-2008J0D01*
G01Y234409D02*
G03I-2008J0D01*
G01X112461Y190909D02*
G03X108956I-1752J980D01*
G01X102461D02*
G03X98956I-1753J980D01*
G01X92717Y224409D02*
G03I-2008J0D01*
G01Y234409D02*
G03I-2008J0D01*
G01Y204409D02*
G03I-2008J0D01*
G01Y214409D02*
G03I-2008J0D01*
G01X92461Y190909D02*
G03X88956I-1753J980D01*
G01X111959Y205659D02*
X112349Y206050D01*
G01X109459Y203159D02*
X109068Y202769D01*
G01X111959Y215659D02*
X112349Y216050D01*
G01X99068Y202769D02*
X99459Y203159D01*
G01X102349Y206050D02*
X101959Y205659D01*
G01X109459Y213159D02*
X109068Y212769D01*
G01X111959Y225659D02*
X112349Y226050D01*
G01X99068Y212769D02*
X99459Y213159D01*
G01X89068Y202769D02*
X89459Y203159D01*
G01X92349Y206050D02*
X91959Y205659D01*
G01X102349Y216050D02*
X101959Y215659D01*
G01X109459Y223159D02*
X109068Y222769D01*
G01X111959Y235659D02*
X112349Y236050D01*
G01X99068Y222769D02*
X99459Y223159D01*
G01X89068Y212769D02*
X89459Y213159D01*
G01X82349Y206050D02*
X81959Y205659D01*
G01X92349Y216050D02*
X91959Y215659D01*
G01X102349Y226050D02*
X101959Y225659D01*
G01X109459Y233159D02*
X109068Y232769D01*
G01X99068D02*
X99459Y233159D01*
G01X89068Y222769D02*
X89459Y223159D01*
G01X82349Y216050D02*
X81959Y215659D01*
G01X92349Y226050D02*
X91959Y225659D01*
G01X102349Y236050D02*
X101959Y235659D01*
G01X89068Y232769D02*
X89459Y233159D01*
G01X82349Y226050D02*
X81959Y225659D01*
G01X92349Y236050D02*
X91959Y235659D01*
G01X82349Y236050D02*
X81959Y235659D01*
G01X119209Y199409D02*
Y249409D01*
G01X112349Y232769D02*
Y236050D01*
G01Y222769D02*
Y226050D01*
G01Y212769D02*
Y216050D01*
G01Y202769D02*
Y206050D01*
G01X112089Y205789D02*
Y203029D01*
G01Y215789D02*
Y213029D01*
G01Y225789D02*
Y223029D01*
G01Y235789D02*
Y233029D01*
G01X111959Y190909D02*
Y192909D01*
G01Y205659D02*
Y203159D01*
G01Y215659D02*
Y213159D01*
G01Y225659D02*
Y223159D01*
G01Y235659D02*
Y233159D01*
G01X109459Y192909D02*
Y190909D01*
G01Y205659D02*
Y203159D01*
G01Y215659D02*
Y213159D01*
G01Y225659D02*
Y223159D01*
G01Y235659D02*
Y233159D01*
G01X109414Y192909D02*
Y190909D01*
G01X109329Y205789D02*
Y203029D01*
G01Y215789D02*
Y213029D01*
G01Y225789D02*
Y223029D01*
G01Y235789D02*
Y233029D01*
G01X109068Y206050D02*
Y202769D01*
G01Y216050D02*
Y212769D01*
G01Y226050D02*
Y222769D01*
G01Y236050D02*
Y232769D01*
G01X104622Y192909D02*
Y190909D01*
G01X102349Y206050D02*
Y202769D01*
G01Y216050D02*
Y212769D01*
G01Y226050D02*
Y222769D01*
G01Y236050D02*
Y232769D01*
G01X102089Y205789D02*
Y203029D01*
G01Y215789D02*
Y213029D01*
G01Y225789D02*
Y223029D01*
G01Y235789D02*
Y233029D01*
G01X101959Y190909D02*
Y192909D01*
G01Y205659D02*
Y203159D01*
G01Y215659D02*
Y213159D01*
G01Y225659D02*
Y223159D01*
G01Y235659D02*
Y233159D01*
G01X99459D02*
Y235659D01*
G01Y223159D02*
Y225659D01*
G01Y213159D02*
Y215659D01*
G01Y203159D02*
Y205659D01*
G01Y192909D02*
Y190909D01*
G01X99329Y233029D02*
Y235789D01*
G01Y223029D02*
Y225789D01*
G01Y213029D02*
Y215789D01*
G01Y203029D02*
Y205789D01*
G01X99068Y232769D02*
Y236050D01*
G01Y222769D02*
Y226050D01*
G01Y212769D02*
Y216050D01*
G01Y202769D02*
Y206050D01*
G01X92349D02*
Y202769D01*
G01Y216050D02*
Y212769D01*
G01Y226050D02*
Y222769D01*
G01Y236050D02*
Y232769D01*
G01X92089Y205789D02*
Y203029D01*
G01Y215789D02*
Y213029D01*
G01Y225789D02*
Y223029D01*
G01Y235789D02*
Y233029D01*
G01X91959Y190909D02*
Y192909D01*
G01Y205659D02*
Y203159D01*
G01Y215659D02*
Y213159D01*
G01Y225659D02*
Y223159D01*
G01Y235659D02*
Y233159D01*
G01X89459D02*
Y235659D01*
G01Y223159D02*
Y225659D01*
G01Y213159D02*
Y215659D01*
G01Y203159D02*
Y205659D01*
G01Y192909D02*
Y190909D01*
G01X89329Y233029D02*
Y235789D01*
G01Y223029D02*
Y225789D01*
G01Y213029D02*
Y215789D01*
G01Y203029D02*
Y205789D01*
G01X89068Y232769D02*
Y236050D01*
G01Y222769D02*
Y226050D01*
G01Y212769D02*
Y216050D01*
G01Y202769D02*
Y206050D01*
G01X83346Y192909D02*
Y190909D01*
G01X82349Y206050D02*
Y202769D01*
G01Y216050D02*
Y212769D01*
G01Y226050D02*
Y222769D01*
G01Y236050D02*
Y232769D01*
G01X82089Y205789D02*
Y203029D01*
G01Y215789D02*
Y213029D01*
G01Y225789D02*
Y223029D01*
G01Y235789D02*
Y233029D01*
G01X81959Y190909D02*
Y192909D01*
G01Y205659D02*
Y203159D01*
G01Y215659D02*
Y213159D01*
G01Y225659D02*
Y223159D01*
G01Y235659D02*
Y233159D01*
G01X111959D02*
X112349Y232769D01*
G01X109068Y236050D02*
X109459Y235659D01*
G01X111959Y223159D02*
X112349Y222769D01*
G01X109068Y226050D02*
X109459Y225659D01*
G01X101959Y233159D02*
X102349Y232769D01*
G01X99068Y236050D02*
X99459Y235659D01*
G01X111959Y213159D02*
X112349Y212769D01*
G01X109068Y216050D02*
X109459Y215659D01*
G01X101959Y223159D02*
X102349Y222769D01*
G01X99068Y226050D02*
X99459Y225659D01*
G01X91959Y233159D02*
X92349Y232769D01*
G01X89068Y236050D02*
X89459Y235659D01*
G01X111959Y203159D02*
X112349Y202769D01*
G01X109068Y206050D02*
X109459Y205659D01*
G01X101959Y213159D02*
X102349Y212769D01*
G01X99068Y216050D02*
X99459Y215659D01*
G01X91959Y223159D02*
X92349Y222769D01*
G01X89068Y226050D02*
X89459Y225659D01*
G01X81959Y233159D02*
X82349Y232769D01*
G01X101959Y203159D02*
X102349Y202769D01*
G01X99068Y206050D02*
X99459Y205659D01*
G01X91959Y213159D02*
X92349Y212769D01*
G01X89068Y216050D02*
X89459Y215659D01*
G01X81959Y223159D02*
X82349Y222769D01*
G01X91959Y203159D02*
X92349Y202769D01*
G01X89068Y206050D02*
X89459Y205659D01*
G01X81959Y213159D02*
X82349Y212769D01*
G01X81959Y203159D02*
X82349Y202769D01*
G01X99068Y236050D02*
X102349D01*
G01X89068D02*
X92349D01*
G01X112349D02*
X109068D01*
G01X109329Y235789D02*
X112089D01*
G01X99329D02*
X102089D01*
G01X89329D02*
X92089D01*
G01X109459Y235659D02*
X111959D01*
G01X99459D02*
X101959D01*
G01X89459D02*
X91959D01*
G01Y233159D02*
X89459D01*
G01X101959D02*
X99459D01*
G01X111959D02*
X109459D01*
G01X92089Y233029D02*
X89329D01*
G01X102089D02*
X99329D01*
G01X112089D02*
X109329D01*
G01X109068Y232769D02*
X112349D01*
G01X92349D02*
X89068D01*
G01X102349D02*
X99068D01*
G01Y226050D02*
X102349D01*
G01X89068D02*
X92349D01*
G01X112349D02*
X109068D01*
G01X109329Y225789D02*
X112089D01*
G01X99329D02*
X102089D01*
G01X89329D02*
X92089D01*
G01X109459Y225659D02*
X111959D01*
G01X99459D02*
X101959D01*
G01X89459D02*
X91959D01*
G01Y223159D02*
X89459D01*
G01X101959D02*
X99459D01*
G01X111959D02*
X109459D01*
G01X92089Y223029D02*
X89329D01*
G01X102089D02*
X99329D01*
G01X112089D02*
X109329D01*
G01X109068Y222769D02*
X112349D01*
G01X92349D02*
X89068D01*
G01X102349D02*
X99068D01*
G01Y216050D02*
X102349D01*
G01X89068D02*
X92349D01*
G01X112349D02*
X109068D01*
G01X109329Y215789D02*
X112089D01*
G01X99329D02*
X102089D01*
G01X89329D02*
X92089D01*
G01X109459Y215659D02*
X111959D01*
G01X99459D02*
X101959D01*
G01X89459D02*
X91959D01*
G01Y213159D02*
X89459D01*
G01X101959D02*
X99459D01*
G01X111959D02*
X109459D01*
G01X92089Y213029D02*
X89329D01*
G01X102089D02*
X99329D01*
G01X112089D02*
X109329D01*
G01X109068Y212769D02*
X112349D01*
G01X92349D02*
X89068D01*
G01X102349D02*
X99068D01*
G01Y206050D02*
X102349D01*
G01X89068D02*
X92349D01*
G01X112349D02*
X109068D01*
G01X109329Y205789D02*
X112089D01*
G01X99329D02*
X102089D01*
G01X89329D02*
X92089D01*
G01X109459Y205659D02*
X111959D01*
G01X99459D02*
X101959D01*
G01X89459D02*
X91959D01*
G01Y203159D02*
X89459D01*
G01X101959D02*
X99459D01*
G01X111959D02*
X109459D01*
G01X92089Y203029D02*
X89329D01*
G01X102089D02*
X99329D01*
G01X112089D02*
X109329D01*
G01X109068Y202769D02*
X112349D01*
G01X92349D02*
X89068D01*
G01X102349D02*
X99068D01*
G01X119209Y199409D02*
X121404D01*
G01X111959Y192909D02*
X109459D01*
G01X108956Y257910D02*
G03X112461I1753J-981D01*
G01X108956Y277910D02*
G03X112461I1753J-981D01*
G01X112438Y265909D02*
G03X108979I-1730J1020D01*
G01X112438Y285909D02*
G03X108979I-1730J1020D01*
G01X112717Y244409D02*
G03I-2008J0D01*
G01X98956Y257910D02*
G03X102461I1753J-981D01*
G01X98956Y277910D02*
G03X102461I1753J-981D01*
G01X102438Y265909D02*
G03X98979I-1730J1020D01*
G01X102438Y285909D02*
G03X98979I-1730J1020D01*
G01X102717Y244409D02*
G03I-2008J0D01*
G01X88956Y277910D02*
G03X92461I1753J-981D01*
G01X92438Y285909D02*
G03X88979I-1729J1020D01*
G01X92717Y244409D02*
G03I-2008J0D01*
G01X88956Y257910D02*
G03X92461I1753J-981D01*
G01X92438Y265909D02*
G03X88979I-1729J1020D01*
G01X83846Y286756D02*
X83771Y286731D01*
G01Y286879D02*
X83846Y286904D01*
G01X83947Y286830D02*
X83846Y286756D01*
G01Y286904D02*
X83896Y286953D01*
G01X111959Y245659D02*
X112349Y246050D01*
G01X109459Y243159D02*
X109068Y242769D01*
G01X99068D02*
X99459Y243159D01*
G01X102349Y246050D02*
X101959Y245659D01*
G01X89068Y242769D02*
X89459Y243159D01*
G01X92349Y246050D02*
X91959Y245659D01*
G01X82349Y246050D02*
X81959Y245659D01*
G01X84022Y286928D02*
X83947Y286830D01*
G01X83896Y286953D02*
X83922Y287027D01*
G01X84047Y287051D02*
X84022Y286928D01*
G01X119409Y249409D02*
Y294409D01*
G01X113339Y265909D02*
Y257909D01*
G01Y285909D02*
Y277909D01*
G01X112349Y242769D02*
Y246050D01*
G01X112089Y245789D02*
Y243029D01*
G01X111959Y285909D02*
Y287909D01*
G01Y275909D02*
Y277909D01*
G01Y265909D02*
Y267909D01*
G01Y255909D02*
Y257909D01*
G01Y245659D02*
Y243159D01*
G01X109459Y245659D02*
Y243159D01*
G01Y257909D02*
Y255909D01*
G01Y267909D02*
Y265909D01*
G01Y277909D02*
Y275909D01*
G01Y287909D02*
Y285909D01*
G01X109414Y257909D02*
Y255909D01*
G01Y267909D02*
Y265909D01*
G01Y277909D02*
Y275909D01*
G01Y287909D02*
Y285909D01*
G01X109329Y245789D02*
Y243029D01*
G01X109068Y246050D02*
Y242769D01*
G01X104622Y257909D02*
Y255909D01*
G01Y267909D02*
Y265909D01*
G01Y277909D02*
Y275909D01*
G01Y287909D02*
Y285909D01*
G01X102349Y246050D02*
Y242769D01*
G01X102089Y245789D02*
Y243029D01*
G01X101959Y285909D02*
Y287909D01*
G01Y275909D02*
Y277909D01*
G01Y265909D02*
Y267909D01*
G01Y255909D02*
Y257909D01*
G01Y245659D02*
Y243159D01*
G01X99459D02*
Y245659D01*
G01Y257909D02*
Y255909D01*
G01Y267909D02*
Y265909D01*
G01Y277909D02*
Y275909D01*
G01Y287909D02*
Y285909D01*
G01X99329Y243029D02*
Y245789D01*
G01X99068Y242769D02*
Y246050D01*
G01X92349D02*
Y242769D01*
G01X92089Y245789D02*
Y243029D01*
G01X91959Y285909D02*
Y287909D01*
G01Y275909D02*
Y277909D01*
G01Y265909D02*
Y267909D01*
G01Y255909D02*
Y257909D01*
G01Y245659D02*
Y243159D01*
G01X89459D02*
Y245659D01*
G01Y257909D02*
Y255909D01*
G01Y267909D02*
Y265909D01*
G01Y277909D02*
Y275909D01*
G01Y287909D02*
Y285909D01*
G01X89329Y243029D02*
Y245789D01*
G01X89068Y242769D02*
Y246050D01*
G01X84047Y286387D02*
Y286239D01*
G01Y287642D02*
Y287051D01*
G01X83922Y287027D02*
Y287494D01*
G01X83545D02*
Y287027D01*
G01X83394Y287051D02*
Y287494D01*
G01X83346Y257909D02*
Y255909D01*
G01Y267909D02*
Y265909D01*
G01Y277909D02*
Y275909D01*
G01Y287909D02*
Y285909D01*
G01X82866Y287494D02*
Y287642D01*
G01Y286239D02*
Y286387D01*
G01X82349Y246050D02*
Y242769D01*
G01X82089Y245789D02*
Y243029D01*
G01X81959Y285909D02*
Y287909D01*
G01Y275909D02*
Y277909D01*
G01Y265909D02*
Y267909D01*
G01Y255909D02*
Y257909D01*
G01Y245659D02*
Y243159D01*
G01X83419Y286928D02*
X83394Y287051D01*
G01X83545Y287027D02*
X83570Y286953D01*
G01X83494Y286830D02*
X83419Y286928D01*
G01X111959Y243159D02*
X112349Y242769D01*
G01X109068Y246050D02*
X109459Y245659D01*
G01X101959Y243159D02*
X102349Y242769D01*
G01X99068Y246050D02*
X99459Y245659D01*
G01X83570Y286953D02*
X83620Y286904D01*
G01X91959Y243159D02*
X92349Y242769D01*
G01X89068Y246050D02*
X89459Y245659D01*
G01X81959Y243159D02*
X82349Y242769D01*
G01X83871Y286534D02*
X84047Y286387D01*
G01X83846D02*
X83670Y286534D01*
G01X83595Y286756D02*
X83494Y286830D01*
G01X83620Y286904D02*
X83695Y286879D01*
G01X83670Y286731D02*
X83595Y286756D01*
G01X111959Y287909D02*
X109459D01*
G01X82866Y287642D02*
X84047D01*
G01X83922Y287494D02*
X83545D01*
G01X83394D02*
X82866D01*
G01X83695Y286879D02*
X83771D01*
G01Y286731D02*
X83670D01*
G01Y286534D02*
X83871D01*
G01X82866Y286387D02*
X83846D01*
G01X84047Y286239D02*
X82866D01*
G01X109459Y275909D02*
X111959D01*
G01Y267909D02*
X109459D01*
G01Y255909D02*
X111959D01*
G01X119209Y249409D02*
X121404D01*
G01X99068Y246050D02*
X102349D01*
G01X89068D02*
X92349D01*
G01X112349D02*
X109068D01*
G01X109329Y245789D02*
X112089D01*
G01X99329D02*
X102089D01*
G01X89329D02*
X92089D01*
G01X109459Y245659D02*
X111959D01*
G01X99459D02*
X101959D01*
G01X89459D02*
X91959D01*
G01Y243159D02*
X89459D01*
G01X101959D02*
X99459D01*
G01X111959D02*
X109459D01*
G01X92089Y243029D02*
X89329D01*
G01X102089D02*
X99329D01*
G01X112089D02*
X109329D01*
G01X109068Y242769D02*
X112349D01*
G01X92349D02*
X89068D01*
G01X102349D02*
X99068D01*
G01X94409Y303409D02*
Y339409D01*
G01Y302909D02*
Y303409D01*
G01X86509Y305409D02*
Y298409D01*
G01X82059Y314359D02*
Y304459D01*
G01X94409Y310909D02*
X124409D01*
G01Y303409D02*
X94409D01*
G01X124409Y302909D02*
X94409D01*
G01X86509Y298409D02*
X121409D01*
G01X113189Y568071D02*
Y566181D01*
G01Y575551D02*
Y573661D01*
G01X112598Y568071D02*
Y566181D01*
G01Y575551D02*
Y573661D01*
G01X112405Y568071D02*
Y566181D01*
G01Y575551D02*
Y573661D01*
G01X112270Y568071D02*
Y566181D01*
G01Y575551D02*
Y573661D01*
G01X111823Y568071D02*
Y566181D01*
G01Y575551D02*
Y573661D01*
G01X111689Y568071D02*
Y566181D01*
G01Y575551D02*
Y573661D01*
G01X111495Y568071D02*
Y566181D01*
G01Y575551D02*
Y573661D01*
G01X111024Y564961D02*
Y576772D01*
G01X105512D02*
Y564961D01*
G01X105041Y571811D02*
Y569921D01*
G01X104847Y571811D02*
Y569921D01*
G01X104712Y571811D02*
Y569921D01*
G01X104265Y571811D02*
Y569921D01*
G01X104131Y571811D02*
Y569921D01*
G01X103937Y571811D02*
Y569921D01*
G01X103346Y571811D02*
Y569921D01*
G01X111024Y576772D02*
X105512D01*
G01X113189Y575551D02*
X111024D01*
G01X113189Y573661D02*
X111024D01*
G01X105512Y571811D02*
X103346D01*
G01X105512Y569921D02*
X103346D01*
G01X113189Y568071D02*
X111024D01*
G01X113189Y566181D02*
X111024D01*
G01X105512Y564961D02*
X111024D01*
G01X123087Y1001721D02*
Y951721D01*
G01X108713Y1001721D02*
X137463D01*
G01X113189Y1262638D02*
X111024D01*
G01X105512Y1260787D02*
X103346D01*
G01X105512Y1258898D02*
X103346D01*
G01X113189Y1257047D02*
X111024D01*
G01X113189Y1255157D02*
X111024D01*
G01X105512Y1253937D02*
X111024D01*
G01X113189Y1257047D02*
Y1255157D01*
G01Y1264528D02*
Y1262638D01*
G01X112598Y1257047D02*
Y1255157D01*
G01Y1264528D02*
Y1262638D01*
G01X112405Y1257047D02*
Y1255157D01*
G01Y1264528D02*
Y1262638D01*
G01X112270Y1257047D02*
Y1255157D01*
G01Y1264528D02*
Y1262638D01*
G01X111823Y1257047D02*
Y1255157D01*
G01Y1264528D02*
Y1262638D01*
G01X111689Y1257047D02*
Y1255157D01*
G01Y1264528D02*
Y1262638D01*
G01X111495Y1257047D02*
Y1255157D01*
G01Y1264528D02*
Y1262638D01*
G01X111024Y1253937D02*
Y1265748D01*
G01X105512D02*
Y1253937D01*
G01X105041Y1260787D02*
Y1258898D01*
G01X104847Y1260787D02*
Y1258898D01*
G01X104712Y1260787D02*
Y1258898D01*
G01X104265Y1260787D02*
Y1258898D01*
G01X104131Y1260787D02*
Y1258898D01*
G01X103937Y1260787D02*
Y1258898D01*
G01X103346Y1260787D02*
Y1258898D01*
G01X111024Y1265748D02*
X105512D01*
G01X113189Y1264528D02*
X111024D01*
G01X123424Y1772125D02*
Y1689960D01*
G01Y1772125D02*
Y1689960D01*
G01X104329Y1747834D02*
G03I-7874J0D01*
G01X104920D02*
G03I-8465J0D01*
G01X105314D02*
G03I-8859J0D01*
G01X105904D02*
G03I-9449J0D01*
G01X106199D02*
G03I-9744J0D01*
G01X106298D02*
G03I-9843J0D01*
G01D02*
G03I-9843J0D01*
G01X111613D02*
G03I-15158J0D01*
G01X112203D02*
G03I-15748J0D01*
G01X119093Y1785511D02*
G03Y1772125I0J-6693D01*
G01Y1785511D02*
G03Y1772125I0J-6693D01*
G01X123424D02*
X119093D01*
G01X123424D02*
X119093D01*
G01X123424Y1769881D02*
X134447D01*
G01X109999D02*
X123424D01*
G01X109999Y1787755D02*
Y1769881D01*
G01X113937Y1775394D02*
X114846Y1773819D01*
G01X123027D02*
X123937Y1775394D01*
G01D02*
X124846Y1773819D01*
G01X114846D02*
X123027D01*
G01X124846D02*
X133027D01*
G01X104329Y1823031D02*
G03I-7874J0D01*
G01X104920D02*
G03I-8465J0D01*
G01X105314D02*
G03I-8859J0D01*
G01X105904D02*
G03I-9449J0D01*
G01X106199D02*
G03I-9744J0D01*
G01X106298D02*
G03I-9843J0D01*
G01D02*
G03I-9843J0D01*
G01X111613D02*
G03I-15158J0D01*
G01X112203D02*
G03I-15748J0D01*
G01X123424Y1787755D02*
X109999D01*
G01X134447D02*
X123424D01*
G01Y1785511D02*
X119093D01*
G01X123424D02*
X119093D01*
G01X123424Y1856889D02*
Y1785511D01*
G01Y1856889D02*
Y1785511D01*
G01X114846Y1783819D02*
X113937Y1782244D01*
G01D02*
Y1775394D01*
G01X120905Y1778819D02*
G03I-1968J0D01*
G01X120196Y1777559D02*
Y1780079D01*
G01D02*
X117677D01*
G01X123027Y1783819D02*
X114846D01*
G01X116417Y1779354D02*
X116599Y1779571D01*
G01Y1779323D02*
X116417Y1779105D01*
G01D02*
Y1779354D01*
G01X116599Y1778111D02*
Y1779323D01*
G01X116782Y1779571D02*
Y1778111D01*
G01X117677Y1780079D02*
Y1777559D01*
G01D02*
X120196D01*
G01X116782Y1778111D02*
X116599D01*
G01Y1779571D02*
X116782D01*
G01X124846Y1783819D02*
X123937Y1782244D01*
G01X127677Y1780079D02*
Y1777559D01*
G01X123937Y1782244D02*
X123027Y1783819D01*
G01X127677Y1777559D02*
X130196D01*
G01Y1780079D02*
X127677D01*
G01X130905Y1778819D02*
G03I-1968J0D01*
G01X130196Y1777559D02*
Y1780079D01*
G01X133027Y1783819D02*
X124846D01*
G01X118011Y1968504D02*
X142520D01*
G01X109377D02*
X110137D01*
G01X109377D02*
X80709D01*
G01X110137D02*
G03X118011I3937J0D01*
G01X109377D02*
X80709D01*
G01X110137D02*
G03X118011I3937J0D01*
G01X114074D02*
Y1968110D01*
G01Y1968504D02*
Y1968898D01*
G01X113582Y1968504D02*
X114566D01*
G01X131433Y2112671D02*
Y2093734D01*
G01X168110Y31496D02*
G03Y39370I0J3937D01*
G01Y31496D02*
G03Y39370I0J3937D01*
G01X186024Y78740D02*
G03I-6890J0D01*
G01X154508Y139409D02*
G03I-4902J0D01*
G01X155706Y119409D02*
G03I-6100J0D01*
G01X155866D02*
G03I-6260J0D01*
G01X163306Y109409D02*
Y145409D01*
G01X150956Y144359D02*
Y134459D01*
G01X148256D02*
Y144359D01*
G01X135906Y109409D02*
Y339409D01*
G01X193306Y137909D02*
X163306D01*
G01X150956Y134459D02*
X148256D01*
G01X135906Y109409D02*
X163306D01*
G01X177877Y182910D02*
G03X181336I1730J-1020D01*
G01X181358Y170909D02*
G03X177854I-1752J981D01*
G01X167877Y182910D02*
G03X171336I1730J-1020D01*
G01X171358Y170909D02*
G03X167854I-1752J981D01*
G01X157877Y182910D02*
G03X161336I1730J-1020D01*
G01X161358Y170909D02*
G03X157854I-1752J981D01*
G01X177877Y162910D02*
G03X181336I1730J-1020D01*
G01X167877D02*
G03X171336I1730J-1020D01*
G01X157877D02*
G03X161336I1730J-1020D01*
G01X147877D02*
G03X151336I1730J-1020D01*
G01X147877Y182910D02*
G03X151336I1730J-1020D01*
G01X151358Y170909D02*
G03X147854I-1752J981D01*
G01X182236D02*
Y162909D01*
G01Y190909D02*
Y182909D01*
G01X180856Y180909D02*
Y182909D01*
G01Y170909D02*
Y172909D01*
G01Y160909D02*
Y162909D01*
G01X178356D02*
Y160909D01*
G01Y172909D02*
Y170909D01*
G01Y182909D02*
Y180909D01*
G01X178312Y162909D02*
Y160909D01*
G01Y172909D02*
Y170909D01*
G01Y182909D02*
Y180909D01*
G01X173519Y162909D02*
Y160909D01*
G01Y172909D02*
Y170909D01*
G01Y182909D02*
Y180909D01*
G01X170856D02*
Y182909D01*
G01Y170909D02*
Y172909D01*
G01Y160909D02*
Y162909D01*
G01X168356D02*
Y160909D01*
G01Y172909D02*
Y170909D01*
G01Y182909D02*
Y180909D01*
G01X163306Y145409D02*
Y145909D01*
G01X160856Y180909D02*
Y182909D01*
G01Y170909D02*
Y172909D01*
G01Y160909D02*
Y162909D01*
G01X158356D02*
Y160909D01*
G01Y172909D02*
Y170909D01*
G01Y182909D02*
Y180909D01*
G01X155406Y150409D02*
Y143409D01*
G01X152243Y162909D02*
Y160909D01*
G01Y172909D02*
Y170909D01*
G01Y182909D02*
Y180909D01*
G01X150856D02*
Y182909D01*
G01Y170909D02*
Y172909D01*
G01Y160909D02*
Y162909D01*
G01X148356D02*
Y160909D01*
G01Y172909D02*
Y170909D01*
G01Y182909D02*
Y180909D01*
G01X147451D02*
Y182909D01*
G01Y170909D02*
Y172909D01*
G01Y160909D02*
Y162909D01*
G01X146836Y182909D02*
Y190909D01*
G01Y162909D02*
Y170909D01*
G01X140906Y154409D02*
Y199409D01*
G01X138906Y143409D02*
Y305409D01*
G01X146836Y182909D02*
X182236D01*
G01X178356Y180909D02*
X180856D01*
G01X147451D02*
X178312D01*
G01X147451Y172909D02*
X178312D01*
G01X180856D02*
X178356D01*
G01X146836Y170909D02*
X182236D01*
G01X146836Y162909D02*
X182236D01*
G01X178356Y160909D02*
X180856D01*
G01X147451D02*
X178312D01*
G01X138906Y154409D02*
X190306D01*
G01Y150409D02*
X155406D01*
G01X163306Y145909D02*
X193306D01*
G01X163306Y145409D02*
X193306D01*
G01X148256Y144359D02*
X150956D01*
G01X155406Y143409D02*
X138906D01*
G01X135906Y139409D02*
X163306D01*
G01X181614Y234409D02*
G03I-2008J0D01*
G01X171614D02*
G03I-2008J0D01*
G01X181614Y204409D02*
G03I-2008J0D01*
G01Y214409D02*
G03I-2008J0D01*
G01Y224409D02*
G03I-2008J0D01*
G01X181358Y190909D02*
G03X177854I-1752J981D01*
G01X171614Y204409D02*
G03I-2008J0D01*
G01Y214409D02*
G03I-2008J0D01*
G01Y224409D02*
G03I-2008J0D01*
G01X171358Y190909D02*
G03X167854I-1752J981D01*
G01X161614Y234409D02*
G03I-2008J0D01*
G01Y204409D02*
G03I-2008J0D01*
G01Y214409D02*
G03I-2008J0D01*
G01Y224409D02*
G03I-2008J0D01*
G01X161358Y190909D02*
G03X157854I-1752J981D01*
G01X151614Y204409D02*
G03I-2008J0D01*
G01Y214409D02*
G03I-2008J0D01*
G01Y224409D02*
G03I-2008J0D01*
G01Y234409D02*
G03I-2008J0D01*
G01X151358Y190909D02*
G03X147854I-1752J981D01*
G01X180856Y205659D02*
X181247Y206050D01*
G01X178356Y203159D02*
X177966Y202769D01*
G01X180856Y215659D02*
X181247Y216050D01*
G01X167966Y202769D02*
X168356Y203159D01*
G01X171247Y206050D02*
X170856Y205659D01*
G01X178356Y213159D02*
X177966Y212769D01*
G01X180856Y225659D02*
X181247Y226050D01*
G01X167966Y212769D02*
X168356Y213159D01*
G01X157966Y202769D02*
X158356Y203159D01*
G01X161247Y206050D02*
X160856Y205659D01*
G01X171247Y216050D02*
X170856Y215659D01*
G01X178356Y223159D02*
X177966Y222769D01*
G01X180856Y235659D02*
X181247Y236050D01*
G01X167966Y222769D02*
X168356Y223159D01*
G01X157966Y212769D02*
X158356Y213159D01*
G01X147966Y202769D02*
X148356Y203159D01*
G01X151247Y206050D02*
X150856Y205659D01*
G01X161247Y216050D02*
X160856Y215659D01*
G01X171247Y226050D02*
X170856Y225659D01*
G01X178356Y233159D02*
X177966Y232769D01*
G01X167966D02*
X168356Y233159D01*
G01X157966Y222769D02*
X158356Y223159D01*
G01X147966Y212769D02*
X148356Y213159D01*
G01X151247Y216050D02*
X150856Y215659D01*
G01X161247Y226050D02*
X160856Y225659D01*
G01X171247Y236050D02*
X170856Y235659D01*
G01X157966Y232769D02*
X158356Y233159D01*
G01X147966Y222769D02*
X148356Y223159D01*
G01X151247Y226050D02*
X150856Y225659D01*
G01X161247Y236050D02*
X160856Y235659D01*
G01X147966Y232769D02*
X148356Y233159D01*
G01X151247Y236050D02*
X150856Y235659D01*
G01X181247Y232769D02*
Y236050D01*
G01Y222769D02*
Y226050D01*
G01Y212769D02*
Y216050D01*
G01Y202769D02*
Y206050D01*
G01X180986Y205789D02*
Y203029D01*
G01Y215789D02*
Y213029D01*
G01Y225789D02*
Y223029D01*
G01Y235789D02*
Y233029D01*
G01X180856Y190909D02*
Y192909D01*
G01Y205659D02*
Y203159D01*
G01Y215659D02*
Y213159D01*
G01Y225659D02*
Y223159D01*
G01Y235659D02*
Y233159D01*
G01X178356Y192909D02*
Y190909D01*
G01Y205659D02*
Y203159D01*
G01Y215659D02*
Y213159D01*
G01Y225659D02*
Y223159D01*
G01Y235659D02*
Y233159D01*
G01X178312Y192909D02*
Y190909D01*
G01X178226Y205789D02*
Y203029D01*
G01Y215789D02*
Y213029D01*
G01Y225789D02*
Y223029D01*
G01Y235789D02*
Y233029D01*
G01X177966Y206050D02*
Y202769D01*
G01Y216050D02*
Y212769D01*
G01Y226050D02*
Y222769D01*
G01Y236050D02*
Y232769D01*
G01X173519Y192909D02*
Y190909D01*
G01X171247Y206050D02*
Y202769D01*
G01Y216050D02*
Y212769D01*
G01Y226050D02*
Y222769D01*
G01Y236050D02*
Y232769D01*
G01X170986Y205789D02*
Y203029D01*
G01Y215789D02*
Y213029D01*
G01Y225789D02*
Y223029D01*
G01Y235789D02*
Y233029D01*
G01X170856Y190909D02*
Y192909D01*
G01Y205659D02*
Y203159D01*
G01Y215659D02*
Y213159D01*
G01Y225659D02*
Y223159D01*
G01Y235659D02*
Y233159D01*
G01X168356D02*
Y235659D01*
G01Y223159D02*
Y225659D01*
G01Y213159D02*
Y215659D01*
G01Y203159D02*
Y205659D01*
G01Y192909D02*
Y190909D01*
G01X168226Y233029D02*
Y235789D01*
G01Y223029D02*
Y225789D01*
G01Y213029D02*
Y215789D01*
G01Y203029D02*
Y205789D01*
G01X167966Y232769D02*
Y236050D01*
G01Y222769D02*
Y226050D01*
G01Y212769D02*
Y216050D01*
G01Y202769D02*
Y206050D01*
G01X161247D02*
Y202769D01*
G01Y216050D02*
Y212769D01*
G01Y226050D02*
Y222769D01*
G01Y236050D02*
Y232769D01*
G01X160986Y205789D02*
Y203029D01*
G01Y215789D02*
Y213029D01*
G01Y225789D02*
Y223029D01*
G01Y235789D02*
Y233029D01*
G01X160856Y190909D02*
Y192909D01*
G01Y205659D02*
Y203159D01*
G01Y215659D02*
Y213159D01*
G01Y225659D02*
Y223159D01*
G01Y235659D02*
Y233159D01*
G01X158356D02*
Y235659D01*
G01Y223159D02*
Y225659D01*
G01Y213159D02*
Y215659D01*
G01Y203159D02*
Y205659D01*
G01Y192909D02*
Y190909D01*
G01X158226Y233029D02*
Y235789D01*
G01Y223029D02*
Y225789D01*
G01Y213029D02*
Y215789D01*
G01Y203029D02*
Y205789D01*
G01X157966Y232769D02*
Y236050D01*
G01Y222769D02*
Y226050D01*
G01Y212769D02*
Y216050D01*
G01Y202769D02*
Y206050D01*
G01X152243Y192909D02*
Y190909D01*
G01X151247Y206050D02*
Y202769D01*
G01Y216050D02*
Y212769D01*
G01Y226050D02*
Y222769D01*
G01Y236050D02*
Y232769D01*
G01X150986Y205789D02*
Y203029D01*
G01Y215789D02*
Y213029D01*
G01Y225789D02*
Y223029D01*
G01Y235789D02*
Y233029D01*
G01X150856Y190909D02*
Y192909D01*
G01Y205659D02*
Y203159D01*
G01Y215659D02*
Y213159D01*
G01Y225659D02*
Y223159D01*
G01Y235659D02*
Y233159D01*
G01X148356D02*
Y235659D01*
G01Y223159D02*
Y225659D01*
G01Y213159D02*
Y215659D01*
G01Y203159D02*
Y205659D01*
G01Y192909D02*
Y190909D01*
G01X148226Y233029D02*
Y235789D01*
G01Y223029D02*
Y225789D01*
G01Y213029D02*
Y215789D01*
G01Y203029D02*
Y205789D01*
G01X147966Y232769D02*
Y236050D01*
G01Y222769D02*
Y226050D01*
G01Y212769D02*
Y216050D01*
G01Y202769D02*
Y206050D01*
G01X147451Y190909D02*
Y192909D01*
G01X141106Y199409D02*
Y249409D01*
G01X180856Y233159D02*
X181247Y232769D01*
G01X177966Y236050D02*
X178356Y235659D01*
G01X180856Y223159D02*
X181247Y222769D01*
G01X177966Y226050D02*
X178356Y225659D01*
G01X170856Y233159D02*
X171247Y232769D01*
G01X167966Y236050D02*
X168356Y235659D01*
G01X180856Y213159D02*
X181247Y212769D01*
G01X177966Y216050D02*
X178356Y215659D01*
G01X170856Y223159D02*
X171247Y222769D01*
G01X167966Y226050D02*
X168356Y225659D01*
G01X160856Y233159D02*
X161247Y232769D01*
G01X157966Y236050D02*
X158356Y235659D01*
G01X180856Y203159D02*
X181247Y202769D01*
G01X177966Y206050D02*
X178356Y205659D01*
G01X170856Y213159D02*
X171247Y212769D01*
G01X167966Y216050D02*
X168356Y215659D01*
G01X160856Y223159D02*
X161247Y222769D01*
G01X157966Y226050D02*
X158356Y225659D01*
G01X150856Y233159D02*
X151247Y232769D01*
G01X147966Y236050D02*
X148356Y235659D01*
G01X170856Y203159D02*
X171247Y202769D01*
G01X167966Y206050D02*
X168356Y205659D01*
G01X160856Y213159D02*
X161247Y212769D01*
G01X157966Y216050D02*
X158356Y215659D01*
G01X150856Y223159D02*
X151247Y222769D01*
G01X147966Y226050D02*
X148356Y225659D01*
G01X160856Y203159D02*
X161247Y202769D01*
G01X157966Y206050D02*
X158356Y205659D01*
G01X150856Y213159D02*
X151247Y212769D01*
G01X147966Y216050D02*
X148356Y215659D01*
G01X150856Y203159D02*
X151247Y202769D01*
G01X147966Y206050D02*
X148356Y205659D01*
G01X167966Y236050D02*
X171247D01*
G01X157966D02*
X161247D01*
G01X147966D02*
X151247D01*
G01X181247D02*
X177966D01*
G01X178226Y235789D02*
X180986D01*
G01X168226D02*
X170986D01*
G01X158226D02*
X160986D01*
G01X148226D02*
X150986D01*
G01X178356Y235659D02*
X180856D01*
G01X168356D02*
X170856D01*
G01X158356D02*
X160856D01*
G01X148356D02*
X150856D01*
G01Y233159D02*
X148356D01*
G01X160856D02*
X158356D01*
G01X170856D02*
X168356D01*
G01X180856D02*
X178356D01*
G01X150986Y233029D02*
X148226D01*
G01X160986D02*
X158226D01*
G01X170986D02*
X168226D01*
G01X180986D02*
X178226D01*
G01X177966Y232769D02*
X181247D01*
G01X151247D02*
X147966D01*
G01X161247D02*
X157966D01*
G01X171247D02*
X167966D01*
G01Y226050D02*
X171247D01*
G01X157966D02*
X161247D01*
G01X147966D02*
X151247D01*
G01X181247D02*
X177966D01*
G01X178226Y225789D02*
X180986D01*
G01X168226D02*
X170986D01*
G01X158226D02*
X160986D01*
G01X148226D02*
X150986D01*
G01X178356Y225659D02*
X180856D01*
G01X168356D02*
X170856D01*
G01X158356D02*
X160856D01*
G01X148356D02*
X150856D01*
G01Y223159D02*
X148356D01*
G01X160856D02*
X158356D01*
G01X170856D02*
X168356D01*
G01X180856D02*
X178356D01*
G01X150986Y223029D02*
X148226D01*
G01X160986D02*
X158226D01*
G01X170986D02*
X168226D01*
G01X180986D02*
X178226D01*
G01X177966Y222769D02*
X181247D01*
G01X151247D02*
X147966D01*
G01X161247D02*
X157966D01*
G01X171247D02*
X167966D01*
G01Y216050D02*
X171247D01*
G01X157966D02*
X161247D01*
G01X147966D02*
X151247D01*
G01X181247D02*
X177966D01*
G01X178226Y215789D02*
X180986D01*
G01X168226D02*
X170986D01*
G01X158226D02*
X160986D01*
G01X148226D02*
X150986D01*
G01X178356Y215659D02*
X180856D01*
G01X168356D02*
X170856D01*
G01X158356D02*
X160856D01*
G01X148356D02*
X150856D01*
G01Y213159D02*
X148356D01*
G01X160856D02*
X158356D01*
G01X170856D02*
X168356D01*
G01X180856D02*
X178356D01*
G01X150986Y213029D02*
X148226D01*
G01X160986D02*
X158226D01*
G01X170986D02*
X168226D01*
G01X180986D02*
X178226D01*
G01X177966Y212769D02*
X181247D01*
G01X151247D02*
X147966D01*
G01X161247D02*
X157966D01*
G01X171247D02*
X167966D01*
G01Y206050D02*
X171247D01*
G01X157966D02*
X161247D01*
G01X147966D02*
X151247D01*
G01X181247D02*
X177966D01*
G01X178226Y205789D02*
X180986D01*
G01X168226D02*
X170986D01*
G01X158226D02*
X160986D01*
G01X148226D02*
X150986D01*
G01X178356Y205659D02*
X180856D01*
G01X168356D02*
X170856D01*
G01X158356D02*
X160856D01*
G01X148356D02*
X150856D01*
G01Y203159D02*
X148356D01*
G01X160856D02*
X158356D01*
G01X170856D02*
X168356D01*
G01X180856D02*
X178356D01*
G01X150986Y203029D02*
X148226D01*
G01X160986D02*
X158226D01*
G01X170986D02*
X168226D01*
G01X180986D02*
X178226D01*
G01X177966Y202769D02*
X181247D01*
G01X151247D02*
X147966D01*
G01X161247D02*
X157966D01*
G01X171247D02*
X167966D01*
G01X138911Y199409D02*
X141106D01*
G01X147451Y192909D02*
X178312D01*
G01X180856D02*
X178356D01*
G01X146836Y190909D02*
X182236D01*
G01X177854Y277910D02*
G03X181358I1752J-981D01*
G01X181336Y265909D02*
G03X177877I-1729J1020D01*
G01X181336Y285909D02*
G03X177877I-1729J1020D01*
G01X181614Y244409D02*
G03I-2008J0D01*
G01X177854Y257910D02*
G03X181358I1752J-981D01*
G01X167854Y277910D02*
G03X171358I1752J-981D01*
G01X171336Y265909D02*
G03X167877I-1729J1020D01*
G01X171336Y285909D02*
G03X167877I-1729J1020D01*
G01X171614Y244409D02*
G03I-2008J0D01*
G01X167854Y257910D02*
G03X171358I1752J-981D01*
G01X161614Y244409D02*
G03I-2008J0D01*
G01X157854Y257910D02*
G03X161358I1752J-981D01*
G01X157854Y277910D02*
G03X161358I1752J-981D01*
G01X161336Y265909D02*
G03X157877I-1729J1020D01*
G01X161336Y285909D02*
G03X157877I-1729J1020D01*
G01X151614Y244409D02*
G03I-2008J0D01*
G01X147854Y257910D02*
G03X151358I1752J-981D01*
G01X147854Y277910D02*
G03X151358I1752J-981D01*
G01X151336Y265909D02*
G03X147877I-1730J1020D01*
G01X151336Y285909D02*
G03X147877I-1730J1020D01*
G01X152744Y286756D02*
X152668Y286731D01*
G01Y286879D02*
X152744Y286904D01*
G01X152844Y286830D02*
X152744Y286756D01*
G01Y286904D02*
X152794Y286953D01*
G01X180856Y245659D02*
X181247Y246050D01*
G01X178356Y243159D02*
X177966Y242769D01*
G01X167966D02*
X168356Y243159D01*
G01X171247Y246050D02*
X170856Y245659D01*
G01X157966Y242769D02*
X158356Y243159D01*
G01X161247Y246050D02*
X160856Y245659D01*
G01X147966Y242769D02*
X148356Y243159D01*
G01X151247Y246050D02*
X150856Y245659D01*
G01X152920Y286928D02*
X152844Y286830D01*
G01X152794Y286953D02*
X152819Y287027D01*
G01X152945Y287051D02*
X152920Y286928D01*
G01X182236Y265909D02*
Y257909D01*
G01Y285909D02*
Y277909D01*
G01X181247Y242769D02*
Y246050D01*
G01X180986Y245789D02*
Y243029D01*
G01X180856Y285909D02*
Y287909D01*
G01Y275909D02*
Y277909D01*
G01Y265909D02*
Y267909D01*
G01Y255909D02*
Y257909D01*
G01Y245659D02*
Y243159D01*
G01X178356Y245659D02*
Y243159D01*
G01Y257909D02*
Y255909D01*
G01Y267909D02*
Y265909D01*
G01Y277909D02*
Y275909D01*
G01Y287909D02*
Y285909D01*
G01X178312Y257909D02*
Y255909D01*
G01Y267909D02*
Y265909D01*
G01Y277909D02*
Y275909D01*
G01Y287909D02*
Y285909D01*
G01X178226Y245789D02*
Y243029D01*
G01X177966Y246050D02*
Y242769D01*
G01X173519Y257909D02*
Y255909D01*
G01Y267909D02*
Y265909D01*
G01Y277909D02*
Y275909D01*
G01Y287909D02*
Y285909D01*
G01X171247Y246050D02*
Y242769D01*
G01X170986Y245789D02*
Y243029D01*
G01X170856Y285909D02*
Y287909D01*
G01Y275909D02*
Y277909D01*
G01Y265909D02*
Y267909D01*
G01Y255909D02*
Y257909D01*
G01Y245659D02*
Y243159D01*
G01X168356D02*
Y245659D01*
G01Y257909D02*
Y255909D01*
G01Y267909D02*
Y265909D01*
G01Y277909D02*
Y275909D01*
G01Y287909D02*
Y285909D01*
G01X168226Y243029D02*
Y245789D01*
G01X167966Y242769D02*
Y246050D01*
G01X161247D02*
Y242769D01*
G01X160986Y245789D02*
Y243029D01*
G01X160856Y285909D02*
Y287909D01*
G01Y275909D02*
Y277909D01*
G01Y265909D02*
Y267909D01*
G01Y255909D02*
Y257909D01*
G01Y245659D02*
Y243159D01*
G01X158356D02*
Y245659D01*
G01Y257909D02*
Y255909D01*
G01Y267909D02*
Y265909D01*
G01Y277909D02*
Y275909D01*
G01Y287909D02*
Y285909D01*
G01X158226Y243029D02*
Y245789D01*
G01X157966Y242769D02*
Y246050D01*
G01X152945Y286387D02*
Y286239D01*
G01Y287642D02*
Y287051D01*
G01X152819Y287027D02*
Y287494D01*
G01X152442D02*
Y287027D01*
G01X152292Y287051D02*
Y287494D01*
G01X152243Y257909D02*
Y255909D01*
G01Y267909D02*
Y265909D01*
G01Y277909D02*
Y275909D01*
G01Y287909D02*
Y285909D01*
G01X151764Y287494D02*
Y287642D01*
G01Y286239D02*
Y286387D01*
G01X151247Y246050D02*
Y242769D01*
G01X150986Y245789D02*
Y243029D01*
G01X150856Y285909D02*
Y287909D01*
G01Y275909D02*
Y277909D01*
G01Y265909D02*
Y267909D01*
G01Y255909D02*
Y257909D01*
G01Y245659D02*
Y243159D01*
G01X148356D02*
Y245659D01*
G01Y257909D02*
Y255909D01*
G01Y267909D02*
Y265909D01*
G01Y277909D02*
Y275909D01*
G01Y287909D02*
Y285909D01*
G01X148226Y243029D02*
Y245789D01*
G01X147966Y242769D02*
Y246050D01*
G01X147451Y285909D02*
Y287909D01*
G01Y275909D02*
Y277909D01*
G01Y265909D02*
Y267909D01*
G01Y255909D02*
Y257909D01*
G01X146836Y277909D02*
Y285909D01*
G01Y257909D02*
Y265909D01*
G01X140906Y249409D02*
Y294409D01*
G01X152317Y286928D02*
X152292Y287051D01*
G01X152442Y287027D02*
X152467Y286953D01*
G01X152392Y286830D02*
X152317Y286928D01*
G01X180856Y243159D02*
X181247Y242769D01*
G01X177966Y246050D02*
X178356Y245659D01*
G01X170856Y243159D02*
X171247Y242769D01*
G01X167966Y246050D02*
X168356Y245659D01*
G01X160856Y243159D02*
X161247Y242769D01*
G01X157966Y246050D02*
X158356Y245659D01*
G01X150856Y243159D02*
X151247Y242769D01*
G01X147966Y246050D02*
X148356Y245659D01*
G01X152467Y286953D02*
X152518Y286904D01*
G01X152769Y286534D02*
X152945Y286387D01*
G01X152744D02*
X152568Y286534D01*
G01X152493Y286756D02*
X152392Y286830D01*
G01X152518Y286904D02*
X152593Y286879D01*
G01X152568Y286731D02*
X152493Y286756D01*
G01X147451Y287909D02*
X178312D01*
G01X180856D02*
X178356D01*
G01X151764Y287642D02*
X152945D01*
G01X152292Y287494D02*
X151764D01*
G01X152819D02*
X152442D01*
G01X152593Y286879D02*
X152668D01*
G01Y286731D02*
X152568D01*
G01Y286534D02*
X152769D01*
G01X151764Y286387D02*
X152744D01*
G01X152945Y286239D02*
X151764D01*
G01X146836Y285909D02*
X182236D01*
G01X146836Y277909D02*
X182236D01*
G01X178356Y275909D02*
X180856D01*
G01X147451D02*
X178312D01*
G01X147451Y267909D02*
X178312D01*
G01X180856D02*
X178356D01*
G01X146836Y265909D02*
X182236D01*
G01X146836Y257909D02*
X182236D01*
G01X178356Y255909D02*
X180856D01*
G01X147451D02*
X178312D01*
G01X138911Y249409D02*
X141106D01*
G01X167966Y246050D02*
X171247D01*
G01X157966D02*
X161247D01*
G01X147966D02*
X151247D01*
G01X181247D02*
X177966D01*
G01X178226Y245789D02*
X180986D01*
G01X168226D02*
X170986D01*
G01X158226D02*
X160986D01*
G01X148226D02*
X150986D01*
G01X178356Y245659D02*
X180856D01*
G01X168356D02*
X170856D01*
G01X158356D02*
X160856D01*
G01X148356D02*
X150856D01*
G01Y243159D02*
X148356D01*
G01X160856D02*
X158356D01*
G01X170856D02*
X168356D01*
G01X180856D02*
X178356D01*
G01X150986Y243029D02*
X148226D01*
G01X160986D02*
X158226D01*
G01X170986D02*
X168226D01*
G01X180986D02*
X178226D01*
G01X177966Y242769D02*
X181247D01*
G01X151247D02*
X147966D01*
G01X161247D02*
X157966D01*
G01X171247D02*
X167966D01*
G01X154508Y309409D02*
G03I-4902J0D01*
G01X155706Y329409D02*
G03I-6100J0D01*
G01X155866D02*
G03I-6260J0D01*
G01X163306Y303409D02*
Y339409D01*
G01Y302909D02*
Y303409D01*
G01X155406Y305409D02*
Y298409D01*
G01X150956Y314359D02*
Y304459D01*
G01X148256D02*
Y314359D01*
G01X163306Y339409D02*
X135906D01*
G01X148256Y314359D02*
X150956D01*
G01X163306Y310909D02*
X193306D01*
G01X163306Y309409D02*
X135906D01*
G01X138906Y305409D02*
X155406D01*
G01X150956Y304459D02*
X148256D01*
G01X193306Y303409D02*
X163306D01*
G01X193306Y302909D02*
X163306D01*
G01X155406Y298409D02*
X190306D01*
G01X138906Y294409D02*
X190306D01*
G01X186024Y570866D02*
G03I-6890J0D01*
G01Y1161417D02*
G03I-6890J0D01*
G01X194094Y1328740D02*
G03I-15157J0D01*
G01X194685D02*
G03I-15748J0D01*
G01X197638D02*
G03I-18701J0D01*
G01X186811D02*
G03I-7874J0D01*
G01X187402D02*
G03I-8465J0D01*
G01X187795D02*
G03I-8858J0D01*
G01X188386D02*
G03I-9449J0D01*
G01X188780D02*
G03I-9843J0D01*
G01X188384Y1689960D02*
X134447D01*
G01X188384D02*
X134447D01*
G01D02*
Y1772125D01*
G01Y1689960D02*
Y1772125D01*
G01X180117Y1747834D02*
G03I-18701J0D01*
G01X138778Y1772125D02*
G03Y1785511I0J6693D01*
G01Y1772125D02*
G03Y1785511I0J6693D01*
G01X134447Y1772125D02*
X138778D01*
G01X134447D02*
X138778D01*
G01X134447Y1769881D02*
X147873D01*
G01D02*
Y1787755D01*
G01X169290Y1747834D02*
G03I-7874J0D01*
G01X169880D02*
G03I-8464J0D01*
G01X170274D02*
G03I-8858J0D01*
G01X170865D02*
G03I-9449J0D01*
G01X171160D02*
G03I-9744J0D01*
G01X171258D02*
G03I-9842J0D01*
G01D02*
G03I-9842J0D01*
G01X176573D02*
G03I-15157J0D01*
G01X177164D02*
G03I-15748J0D01*
G01X133027Y1773819D02*
X133937Y1775394D01*
G01D02*
X134846Y1773819D01*
G01D02*
X143027D01*
G01D02*
X143937Y1775394D01*
G01X180117Y1823031D02*
G03I-18701J0D01*
G01X147873Y1787755D02*
X134447D01*
G01Y1785511D02*
X138778D01*
G01X134447D02*
X138778D01*
G01X134447D02*
Y1856889D01*
G01Y1785511D02*
Y1856889D01*
G01X169290Y1823031D02*
G03I-7874J0D01*
G01X169880D02*
G03I-8464J0D01*
G01X170274D02*
G03I-8858J0D01*
G01X170865D02*
G03I-9449J0D01*
G01X171160D02*
G03I-9744J0D01*
G01X171258D02*
G03I-9842J0D01*
G01D02*
G03I-9842J0D01*
G01X176573D02*
G03I-15157J0D01*
G01X177164D02*
G03I-15748J0D01*
G01X134846Y1783819D02*
X133937Y1782244D01*
G01X137677Y1780079D02*
Y1777559D01*
G01X133937Y1782244D02*
X133027Y1783819D01*
G01X137677Y1777559D02*
X140196D01*
G01Y1780079D02*
X137677D01*
G01X143027Y1783819D02*
X134846D01*
G01X140905Y1778819D02*
G03I-1968J0D01*
G01X141881Y1778618D02*
X142209Y1778730D01*
G01X141115Y1779624D02*
X141334Y1779736D01*
G01X142209Y1777501D02*
X142319Y1777557D01*
G01X142428Y1777333D02*
X142209Y1777221D01*
G01X142538Y1778674D02*
X142319Y1778507D01*
G01X141389Y1779456D02*
X141225Y1779345D01*
G01X142592Y1777445D02*
X142428Y1777333D01*
G01X140896Y1779401D02*
X141115Y1779624D01*
G01X142209Y1778730D02*
X142319Y1778842D01*
G01Y1777557D02*
X142428Y1777668D01*
G01X141225Y1779345D02*
X141115Y1779177D01*
G01X142647Y1778842D02*
X142538Y1778674D01*
G01X142702Y1777613D02*
X142592Y1777445D01*
G01X142319Y1778842D02*
X142428Y1779065D01*
G01Y1777668D02*
X142483Y1777780D01*
G01X142756D02*
X142702Y1777613D01*
G01X140842Y1779177D02*
X140896Y1779401D01*
G01X142702Y1779065D02*
X142647Y1778842D01*
G01X140196Y1777559D02*
Y1780079D01*
G01X141662Y1778395D02*
Y1778618D01*
G01X142428Y1779065D02*
Y1779177D01*
G01X142483Y1777780D02*
Y1778004D01*
G01X142702Y1779177D02*
Y1779065D01*
G01X142756Y1778004D02*
Y1777780D01*
G01X142702Y1778227D02*
X142756Y1778004D01*
G01X142647Y1779401D02*
X142702Y1779177D01*
G01X140842Y1777613D02*
X140787Y1777780D01*
G01X141061D02*
X141115Y1777668D01*
G01X142483Y1778004D02*
X142374Y1778227D01*
G01X140951Y1777445D02*
X140842Y1777613D01*
G01X142592Y1778395D02*
X142702Y1778227D01*
G01X142428Y1779177D02*
X142319Y1779345D01*
G01X141115Y1777668D02*
X141225Y1777557D01*
G01X142428Y1779624D02*
X142647Y1779401D01*
G01X141334Y1777221D02*
X141115Y1777333D01*
G01X141225Y1777557D02*
X141334Y1777501D01*
G01X142209Y1779736D02*
X142428Y1779624D01*
G01X141115Y1777333D02*
X140951Y1777445D01*
G01X142374Y1778227D02*
X142209Y1778339D01*
G01X142319Y1779345D02*
X142155Y1779456D01*
G01X142209Y1777221D02*
X141991Y1777166D01*
G01X141936Y1777445D02*
X142209Y1777501D01*
G01X141662Y1779512D02*
X141389Y1779456D01*
G01X141334Y1779736D02*
X141717Y1779792D01*
G01X141991Y1777166D02*
X141553D01*
G01X141608Y1777445D02*
X141936D01*
G01X140787Y1777780D02*
X141061D01*
G01X141881Y1778395D02*
X141662D01*
G01Y1778618D02*
X141881D01*
G01X141115Y1779177D02*
X140842D01*
G01X141881Y1779512D02*
X141662D01*
G01X141717Y1779792D02*
X141826D01*
G01D02*
X142209Y1779736D01*
G01Y1778339D02*
X141881Y1778395D01*
G01X141334Y1777501D02*
X141608Y1777445D01*
G01X142155Y1779456D02*
X141881Y1779512D01*
G01X141553Y1777166D02*
X141334Y1777221D01*
G01X142319Y1778507D02*
X142592Y1778395D01*
G01X143937Y1775394D02*
Y1782244D01*
G01D02*
X143027Y1783819D01*
G01X134447Y1856889D02*
X188384D01*
G01X134447D02*
X188384D01*
G01X187008Y1889764D02*
G03I-7874J0D01*
G01X340559Y1968504D02*
X142520D01*
G01X168110Y1929134D02*
G03Y1937008I0J3937D01*
G01X340559Y1968504D02*
X142520D01*
G01X168110Y1929134D02*
G03Y1937008I0J3937D01*
G01X177064Y1967104D02*
Y1969904D01*
G01X145569Y1967104D02*
Y1969904D01*
G01X222441Y31496D02*
X198819D01*
G01X222441D02*
G03Y39370I0J3937D01*
G01X198819D02*
G03Y31496I0J-3937D01*
G01X222441D02*
X198819D01*
G01X222441D02*
G03Y39370I0J3937D01*
G01X198819D02*
G03Y31496I0J-3937D01*
G01X202756Y39370D02*
G03X206693Y43307I0J3937D01*
G01Y1925197D02*
Y43307D01*
G01X202756Y39370D02*
G03X206693Y43307I0J3937D01*
G01X202756Y39370D02*
G03X206693Y43307I0J3937D01*
G01Y1925197D02*
Y43307D01*
G01Y1925197D02*
Y43307D01*
G01X214567Y161417D02*
Y43307D01*
G01X202756Y39370D02*
G03X206693Y43307I0J3937D01*
G01X202756Y39370D02*
G03X206693Y43307I0J3937D01*
G01Y1925197D02*
Y43307D01*
G01Y1925197D02*
Y43307D01*
G01X202756Y39370D02*
G03X206693Y43307I0J3937D01*
G01X218504Y39370D02*
X348425D01*
G01X214567Y43307D02*
G03X218504Y39370I3937J0D01*
G01X202756D02*
G03X206693Y43307I0J3937D01*
G01X218504Y39370D02*
X348425D01*
G01X214567Y43307D02*
G03X218504Y39370I3937J0D01*
G01X193306Y137909D02*
Y310909D01*
G01X190306Y298409D02*
Y150409D01*
G01X188306Y154409D02*
Y199409D01*
G01X206693Y161417D02*
Y1807087D01*
G01X214567D02*
Y161417D01*
G01Y169291D02*
G03X206693I-3937J0D01*
G01Y161417D02*
Y1807087D01*
G01X214567D02*
Y161417D01*
G01Y169291D02*
G03X206693I-3937J0D01*
G01X188106Y199409D02*
Y249409D01*
G01Y199409D02*
X190302D01*
G01X206693Y200000D02*
G03X214567I3937J0D01*
G01X206693D02*
G03X214567I3937J0D01*
G01X188306Y249409D02*
Y294409D01*
G01X188106Y249409D02*
X190302D01*
G01X214567Y436220D02*
G03X206693I-3937J0D01*
G01X214567D02*
G03X206693I-3937J0D01*
G01Y466929D02*
G03X214567I3937J0D01*
G01X206693D02*
G03X214567I3937J0D01*
G01Y703149D02*
G03X206693I-3937J0D01*
G01Y733858D02*
G03X214567I3937J0D01*
G01Y703149D02*
G03X206693I-3937J0D01*
G01Y733858D02*
G03X214567I3937J0D01*
G01Y970867D02*
G03X206693I-3937J0D01*
G01Y997637D02*
G03X214567I3937J0D01*
G01Y970867D02*
G03X206693I-3937J0D01*
G01Y997637D02*
G03X214567I3937J0D01*
G01X206693Y1265355D02*
G03X214567I3937J0D01*
G01Y1234646D02*
G03X206693I-3937J0D01*
G01Y1265355D02*
G03X214567I3937J0D01*
G01Y1234646D02*
G03X206693I-3937J0D01*
G01X214567Y1501575D02*
G03X206693I-3937J0D01*
G01X214567D02*
G03X206693I-3937J0D01*
G01Y1532284D02*
G03X214567I3937J0D01*
G01X206693D02*
G03X214567I3937J0D01*
G01X188384Y1856889D02*
Y1689960D01*
G01Y1856889D02*
Y1689960D01*
G01X214567Y1768504D02*
G03X206693I-3937J0D01*
G01X214567D02*
G03X206693I-3937J0D01*
G01X214567Y1807087D02*
Y1925197D01*
G01X206693Y1799213D02*
G03X214567I3937J0D01*
G01X206693D02*
G03X214567I3937J0D01*
G01X206693Y1925197D02*
G03X202756Y1929134I-3937J0D01*
G01X206693Y1925443D02*
Y1974916D01*
G01X214567Y1925443D02*
Y1975042D01*
G01X206693Y1925197D02*
G03X202756Y1929134I-3937J0D01*
G01X206693Y1925197D02*
G03X202756Y1929134I-3937J0D01*
G01X206693Y1925197D02*
G03X202756Y1929134I-3937J0D01*
G01X206693Y1925197D02*
G03X202756Y1929134I-3937J0D01*
G01X206693Y1925197D02*
G03X202756Y1929134I-3937J0D01*
G01X218504D02*
G03X214567Y1925197I0J-3937D01*
G01X206693D02*
G03X202756Y1929134I-3937J0D01*
G01X218504D02*
G03X214567Y1925197I0J-3937D01*
G01X206693Y1974916D02*
X205074Y1990664D01*
G01X214567Y1975042D02*
X218027Y1990790D01*
G01X348425Y1929134D02*
X218504D01*
G01X198819Y1937008D02*
X222441D01*
G01X198819D02*
G03Y1929134I0J-3937D01*
G01X222441D02*
G03Y1937008I0J3937D01*
G01X348425Y1929134D02*
X218504D01*
G01X198819Y1937008D02*
X222441D01*
G01X198819D02*
G03Y1929134I0J-3937D01*
G01X222441D02*
G03Y1937008I0J3937D01*
G01X208559Y1967104D02*
Y1969904D01*
G01X221964Y2009733D02*
X214389D01*
X215904Y2008597D01*
G01X221964D02*
Y2010870D01*
G01Y2017308D02*
X214389D01*
X215904Y2016172D01*
G01X221964D02*
Y2018445D01*
G01X218808Y2023084D02*
X217924Y2023747D01*
X217419Y2024315D01*
X217167Y2025073D01*
X217419Y2025736D01*
X217924Y2026209D01*
X218682Y2026588D01*
X219565Y2026683D01*
X220323Y2026588D01*
X221080Y2026209D01*
X221712Y2025641D01*
X221964Y2024978D01*
X221712Y2024221D01*
X220954Y2023558D01*
X219818Y2023179D01*
X218555Y2023084D01*
X216914Y2023274D01*
X216030Y2023558D01*
X215147Y2024031D01*
X214515Y2024694D01*
X214389Y2025357D01*
X214641Y2026020D01*
X215273Y2026493D01*
G01X222216Y2032458D02*
X222090Y2032269D01*
X221838D01*
X221712Y2032458D01*
X221838Y2032648D01*
X222090D01*
X222216Y2032458D01*
G01X214389Y2040033D02*
X214641Y2039276D01*
X215273Y2038708D01*
X216030Y2038329D01*
X217040Y2038045D01*
X218177Y2037950D01*
X219313Y2038045D01*
X220323Y2038329D01*
X221080Y2038708D01*
X221712Y2039276D01*
X221964Y2040033D01*
X221712Y2040791D01*
X221080Y2041359D01*
X220323Y2041738D01*
X219313Y2042022D01*
X218177Y2042117D01*
X217040Y2042022D01*
X216030Y2041738D01*
X215273Y2041359D01*
X214641Y2040791D01*
X214389Y2040033D01*
G01Y2047608D02*
X214641Y2046851D01*
X215273Y2046283D01*
X216030Y2045904D01*
X217040Y2045620D01*
X218177Y2045525D01*
X219313Y2045620D01*
X220323Y2045904D01*
X221080Y2046283D01*
X221712Y2046851D01*
X221964Y2047608D01*
X221712Y2048366D01*
X221080Y2048934D01*
X220323Y2049313D01*
X219313Y2049597D01*
X218177Y2049692D01*
X217040Y2049597D01*
X216030Y2049313D01*
X215273Y2048934D01*
X214641Y2048366D01*
X214389Y2047608D01*
G01X209011Y2009606D02*
X201436D01*
X202951Y2008470D01*
G01X209011D02*
Y2010743D01*
G01Y2017181D02*
X201436D01*
X202951Y2016045D01*
G01X209011D02*
Y2018318D01*
G01Y2025893D02*
X201436D01*
X206865Y2022389D01*
Y2027124D01*
G01X209263Y2032331D02*
X209137Y2032142D01*
X208885D01*
X208759Y2032331D01*
X208885Y2032521D01*
X209137D01*
X209263Y2032331D01*
G01X201436Y2039906D02*
X201688Y2039149D01*
X202320Y2038581D01*
X203077Y2038202D01*
X204087Y2037918D01*
X205224Y2037823D01*
X206360Y2037918D01*
X207370Y2038202D01*
X208127Y2038581D01*
X208759Y2039149D01*
X209011Y2039906D01*
X208759Y2040664D01*
X208127Y2041232D01*
X207370Y2041611D01*
X206360Y2041895D01*
X205224Y2041990D01*
X204087Y2041895D01*
X203077Y2041611D01*
X202320Y2041232D01*
X201688Y2040664D01*
X201436Y2039906D01*
G01Y2047481D02*
X201688Y2046724D01*
X202320Y2046156D01*
X203077Y2045777D01*
X204087Y2045493D01*
X205224Y2045398D01*
X206360Y2045493D01*
X207370Y2045777D01*
X208127Y2046156D01*
X208759Y2046724D01*
X209011Y2047481D01*
X208759Y2048239D01*
X208127Y2048807D01*
X207370Y2049186D01*
X206360Y2049470D01*
X205224Y2049565D01*
X204087Y2049470D01*
X203077Y2049186D01*
X202320Y2048807D01*
X201688Y2048239D01*
X201436Y2047481D01*
G01X205074Y1990664D02*
Y2006412D01*
G01X218027Y1990790D02*
Y2006538D01*
G01X243445Y-80235D02*
Y-68873D01*
X238190Y-77016D01*
X245292D01*
G01X253150Y31496D02*
X344488D01*
G01X253150Y39370D02*
G03Y31496I0J-3937D01*
G01D02*
X344488D01*
G01X253150Y39370D02*
G03Y31496I0J-3937D01*
G01Y1937008D02*
X344496D01*
G01X253150D02*
G03Y1929134I0J-3937D01*
G01Y1937008D02*
X344496D01*
G01X253150D02*
G03Y1929134I0J-3937D01*
G01X271549Y1967104D02*
Y1969904D01*
G01X240054Y1967104D02*
Y1969904D01*
G01X243445Y2097521D02*
Y2108883D01*
X238190Y2100740D01*
X245292D01*
G01X331685Y-65085D02*
X1513280D01*
G01X310688Y936637D02*
Y986637D01*
G01X325062Y936637D02*
X296312D01*
G01X303044Y1967104D02*
Y1969904D01*
G01X351102Y-65085D02*
Y-84022D01*
G01X356299Y0D02*
X417323D01*
G01X352362Y3937D02*
G03X356299Y0I3937J0D01*
G01X352362Y35433D02*
Y3937D01*
G01Y35433D02*
G03X348425Y39370I-3937J0D01*
G01X340551Y0D02*
G03X344488Y3937I0J3937D01*
G01Y7874D02*
Y3937D01*
G01D02*
Y7874D01*
G01X352362D02*
G03X344488I-3937J0D01*
G01Y31496D02*
G03X352362I3937J0D01*
G01X356299Y0D02*
X417323D01*
G01X352362Y3937D02*
G03X356299Y0I3937J0D01*
G01X352362Y35433D02*
Y3937D01*
G01Y35433D02*
G03X348425Y39370I-3937J0D01*
G01X340551Y0D02*
G03X344488Y3937I0J3937D01*
G01Y7874D02*
Y3937D01*
G01D02*
Y7874D01*
G01X352362D02*
G03X344488I-3937J0D01*
G01Y31496D02*
G03X352362I3937J0D01*
G01X348425Y1929134D02*
G03X352362Y1933071I0J3937D01*
G01Y1964567D02*
Y1933071D01*
G01X356299Y1968504D02*
G03X352362Y1964567I0J-3937D01*
G01X417323Y1968504D02*
X356299D01*
G01X344496Y1964567D02*
G03X340559Y1968504I-3937J0D01*
G01X344496Y1960889D02*
Y1964567D01*
G01Y1960889D02*
G03X352370I3937J0D01*
G01Y1937008D02*
G03X344496I-3937J0D01*
G01X348425Y1929134D02*
G03X352362Y1933071I0J3937D01*
G01Y1964567D02*
Y1933071D01*
G01X356299Y1968504D02*
G03X352362Y1964567I0J-3937D01*
G01X417323Y1968504D02*
X356299D01*
G01X344496Y1964567D02*
G03X340559Y1968504I-3937J0D01*
G01X344496Y1960889D02*
Y1964567D01*
G01Y1960889D02*
G03X352370I3937J0D01*
G01Y1937008D02*
G03X344496I-3937J0D01*
G01X351102Y2112671D02*
Y2093734D01*
G01X429134Y3937D02*
G03X433071Y0I3937J0D01*
G01X429134Y1964567D02*
Y3937D01*
G01X433071Y0D02*
X494095D01*
G01X421260Y3937D02*
Y1964567D01*
G01X417323Y0D02*
G03X421260Y3937I0J3937D01*
G01X429134Y11811D02*
G03X421260I-3937J0D01*
G01X429134Y3937D02*
G03X433071Y0I3937J0D01*
G01X429134Y1964567D02*
Y3937D01*
G01X433071Y0D02*
X494095D01*
G01X421260Y3937D02*
Y1964567D01*
G01X417323Y0D02*
G03X421260Y3937I0J3937D01*
G01X429134Y11811D02*
G03X421260I-3937J0D01*
G01Y42520D02*
G03X429134I3937J0D01*
G01X421260D02*
G03X429134I3937J0D01*
G01Y278740D02*
G03X421260I-3937J0D01*
G01X429134D02*
G03X421260I-3937J0D01*
G01Y309449D02*
G03X429134I3937J0D01*
G01X421260D02*
G03X429134I3937J0D01*
G01Y545669D02*
G03X421260I-3937J0D01*
G01X429134D02*
G03X421260I-3937J0D01*
G01Y576378D02*
G03X429134I3937J0D01*
G01X421260D02*
G03X429134I3937J0D01*
G01Y831496D02*
G03X421260I-3937J0D01*
G01X429134D02*
G03X421260I-3937J0D01*
G01Y862205D02*
G03X429134I3937J0D01*
G01X421260D02*
G03X429134I3937J0D01*
G01Y1106299D02*
G03X421260I-3937J0D01*
G01X429134D02*
G03X421260I-3937J0D01*
G01Y1137008D02*
G03X429134I3937J0D01*
G01X421260D02*
G03X429134I3937J0D01*
G01Y1392126D02*
G03X421260I-3937J0D01*
G01X429134D02*
G03X421260I-3937J0D01*
G01Y1422835D02*
G03X429134I3937J0D01*
G01X421260D02*
G03X429134I3937J0D01*
G01Y1659055D02*
G03X421260I-3937J0D01*
G01X429134D02*
G03X421260I-3937J0D01*
G01Y1689764D02*
G03X429134I3937J0D01*
G01X421260D02*
G03X429134I3937J0D01*
G01Y1925984D02*
G03X421260I-3937J0D01*
G01X429134D02*
G03X421260I-3937J0D01*
G01Y1978687D02*
X415810Y1994435D01*
G01X421260Y1956939D02*
Y1978687D01*
G01X429134Y1960027D02*
Y1981957D01*
G01X433071Y1968504D02*
G03X429134Y1964567I0J-3937D01*
G01X494095Y1968504D02*
X433071D01*
G01X421260Y1964567D02*
G03X417323Y1968504I-3937J0D01*
G01X421260Y1956693D02*
G03X429134I3937J0D01*
G01X433071Y1968504D02*
G03X429134Y1964567I0J-3937D01*
G01X494095Y1968504D02*
X433071D01*
G01X421260Y1964567D02*
G03X417323Y1968504I-3937J0D01*
G01X421260Y1956693D02*
G03X429134I3937J0D01*
G01X433071Y1968504D02*
G03X429134Y1964567I0J-3937D01*
G01X421260D02*
G03X417323Y1968504I-3937J0D01*
G01X436880Y2016648D02*
X429305D01*
X430820Y2015512D01*
G01X436880D02*
Y2017785D01*
G01Y2024034D02*
X435239Y2024223D01*
X433850Y2024508D01*
X432587Y2024886D01*
X431199Y2025360D01*
X429305Y2026117D01*
Y2022330D01*
G01Y2031798D02*
X429557Y2031041D01*
X430189Y2030473D01*
X430946Y2030094D01*
X431956Y2029810D01*
X433093Y2029715D01*
X434229Y2029810D01*
X435239Y2030094D01*
X435996Y2030473D01*
X436628Y2031041D01*
X436880Y2031798D01*
X436628Y2032556D01*
X435996Y2033124D01*
X435239Y2033503D01*
X434229Y2033787D01*
X433093Y2033882D01*
X431956Y2033787D01*
X430946Y2033503D01*
X430189Y2033124D01*
X429557Y2032556D01*
X429305Y2031798D01*
G01X437132Y2039373D02*
X437006Y2039184D01*
X436754D01*
X436628Y2039373D01*
X436754Y2039563D01*
X437006D01*
X437132Y2039373D01*
G01X435744Y2044865D02*
X436375Y2045433D01*
X436754Y2046096D01*
X436880Y2046948D01*
X436628Y2047801D01*
X436123Y2048463D01*
X435239Y2048937D01*
X434229Y2049032D01*
X433219Y2048842D01*
X432587Y2048369D01*
X432083Y2047706D01*
X431956Y2047043D01*
X432083Y2046380D01*
X432587Y2045528D01*
X429305Y2045812D01*
Y2048369D01*
G01Y2054523D02*
X429557Y2053766D01*
X430189Y2053198D01*
X430946Y2052819D01*
X431956Y2052535D01*
X433093Y2052440D01*
X434229Y2052535D01*
X435239Y2052819D01*
X435996Y2053198D01*
X436628Y2053766D01*
X436880Y2054523D01*
X436628Y2055281D01*
X435996Y2055849D01*
X435239Y2056228D01*
X434229Y2056512D01*
X433093Y2056607D01*
X431956Y2056512D01*
X430946Y2056228D01*
X430189Y2055849D01*
X429557Y2055281D01*
X429305Y2054523D01*
G01X419747Y2013377D02*
X412172D01*
X413687Y2012241D01*
G01X419747D02*
Y2014514D01*
G01X416591Y2019153D02*
X415707Y2019816D01*
X415202Y2020384D01*
X414950Y2021142D01*
X415202Y2021805D01*
X415707Y2022278D01*
X416465Y2022657D01*
X417348Y2022752D01*
X418106Y2022657D01*
X418863Y2022278D01*
X419495Y2021710D01*
X419747Y2021047D01*
X419495Y2020290D01*
X418737Y2019627D01*
X417601Y2019248D01*
X416338Y2019153D01*
X414697Y2019343D01*
X413813Y2019627D01*
X412930Y2020100D01*
X412298Y2020763D01*
X412172Y2021426D01*
X412424Y2022089D01*
X413056Y2022562D01*
G01X419747Y2028527D02*
X419621Y2029190D01*
X419242Y2029948D01*
X418611Y2030421D01*
X417727Y2030611D01*
X416843Y2030421D01*
X416086Y2029853D01*
X415707Y2029001D01*
Y2028054D01*
X415454Y2027486D01*
X414823Y2027012D01*
X413940Y2026823D01*
X413056Y2027107D01*
X412424Y2027770D01*
X412172Y2028527D01*
X412424Y2029285D01*
X413056Y2029948D01*
X413940Y2030232D01*
X414823Y2030042D01*
X415454Y2029569D01*
X415707Y2029001D01*
Y2028054D01*
X416086Y2027202D01*
X416843Y2026634D01*
X417727Y2026444D01*
X418611Y2026634D01*
X419242Y2027107D01*
X419621Y2027865D01*
X419747Y2028527D01*
G01X419999Y2036102D02*
X419873Y2035913D01*
X419621D01*
X419495Y2036102D01*
X419621Y2036292D01*
X419873D01*
X419999Y2036102D01*
G01X418611Y2041594D02*
X419242Y2042162D01*
X419621Y2042825D01*
X419747Y2043677D01*
X419495Y2044530D01*
X418990Y2045192D01*
X418106Y2045666D01*
X417096Y2045761D01*
X416086Y2045571D01*
X415454Y2045098D01*
X414950Y2044435D01*
X414823Y2043772D01*
X414950Y2043109D01*
X415454Y2042257D01*
X412172Y2042541D01*
Y2045098D01*
G01Y2051252D02*
X412424Y2050495D01*
X413056Y2049927D01*
X413813Y2049548D01*
X414823Y2049264D01*
X415960Y2049169D01*
X417096Y2049264D01*
X418106Y2049548D01*
X418863Y2049927D01*
X419495Y2050495D01*
X419747Y2051252D01*
X419495Y2052010D01*
X418863Y2052578D01*
X418106Y2052957D01*
X417096Y2053241D01*
X415960Y2053336D01*
X414823Y2053241D01*
X413813Y2052957D01*
X413056Y2052578D01*
X412424Y2052010D01*
X412172Y2051252D01*
G01X415810Y1994435D02*
Y2010183D01*
G01X432943Y1997705D02*
Y2013453D01*
G01X429134Y1981957D02*
X432943Y1997705D01*
G01X458286Y-78531D02*
X459138Y-79478D01*
X460133Y-80046D01*
X461411Y-80235D01*
X462689Y-79856D01*
X463683Y-79099D01*
X464394Y-77773D01*
X464536Y-76258D01*
X464252Y-74743D01*
X463541Y-73797D01*
X462547Y-73039D01*
X461553Y-72850D01*
X460559Y-73039D01*
X459281Y-73797D01*
X459707Y-68873D01*
X463541D01*
G01X458286Y2099225D02*
X459138Y2098278D01*
X460133Y2097710D01*
X461411Y2097521D01*
X462689Y2097900D01*
X463683Y2098657D01*
X464394Y2099983D01*
X464536Y2101498D01*
X464252Y2103013D01*
X463541Y2103959D01*
X462547Y2104717D01*
X461553Y2104906D01*
X460559Y2104717D01*
X459281Y2103959D01*
X459707Y2108883D01*
X463541D01*
G01X505897Y0D02*
X648386D01*
G01X501969Y39370D02*
G03X498032Y35433I0J-3937D01*
G01Y3937D02*
Y35433D01*
G01X494095Y0D02*
G03X498032Y3937I0J3937D01*
G01X505897Y7615D02*
Y0D01*
G01X597244Y31496D02*
X505897D01*
G01Y7615D02*
G03X498023I-3937J0D01*
G01Y31496D02*
G03X505897I3937J0D01*
G01X501969Y39370D02*
G03X498032Y35433I0J-3937D01*
G01Y3937D02*
Y35433D01*
G01X494095Y0D02*
G03X498032Y3937I0J3937D01*
G01X505897Y7615D02*
Y0D01*
G01X597244Y31496D02*
X505897D01*
G01Y7615D02*
G03X498023I-3937J0D01*
G01Y31496D02*
G03X505897I3937J0D01*
G01X501969Y39370D02*
X631890D01*
G01X501969D02*
X631890D01*
G01X552221Y1001686D02*
Y951686D01*
G01X537847Y1001686D02*
X566597D01*
G01X505906Y1968504D02*
X648386D01*
G01X498032Y1964567D02*
G03X494095Y1968504I-3937J0D01*
G01X498032Y1933071D02*
Y1960630D01*
G01Y1933071D02*
G03X501969Y1929134I3937J0D01*
G01X631890D02*
X501969D01*
G01X505906Y1960630D02*
Y1968504D01*
G01X597244Y1937008D02*
X505906D01*
G01X498032Y1960630D02*
G03X505906I3937J0D01*
G01Y1937008D02*
G03X498032I-3937J0D01*
G01Y1964567D02*
G03X494095Y1968504I-3937J0D01*
G01X498032Y1933071D02*
Y1964567D01*
G01Y1933071D02*
G03X501969Y1929134I3937J0D01*
G01X631890D02*
X501969D01*
G01X505906Y1960630D02*
Y1968504D01*
G01X597244Y1937008D02*
X505906D01*
G01X498032Y1960630D02*
G03X505906I3937J0D01*
G01Y1937008D02*
G03X498032I-3937J0D01*
G01X570772Y-65085D02*
Y-84022D01*
G01Y2112671D02*
Y2093734D01*
G01X650689Y19685D02*
G03I-6988J0D01*
G01D02*
G03I-6988J0D01*
G01X635827Y31496D02*
G03X643701Y39370I0J7874D01*
G01X635827Y31496D02*
X627953D01*
G01X635827D02*
X627953D01*
G01X597244D02*
G03Y39370I0J3937D01*
G01X627953D02*
G03Y31496I0J-3937D01*
G01X597244D02*
G03Y39370I0J3937D01*
G01X627953D02*
G03Y31496I0J-3937D01*
G01X593704Y29248D02*
X609704D01*
G01Y13248D02*
Y29248D01*
G01X593704Y13248D02*
X609704D01*
G01X593704Y29248D02*
Y13248D01*
G01X599204Y18748D02*
X604204D01*
G01Y23748D02*
X599204D01*
G01Y18748D02*
Y23748D01*
G01X604204D02*
Y18748D01*
G01X601704D02*
Y23748D01*
G01X599204Y21248D02*
X604204D01*
G01X635827Y161417D02*
Y43307D01*
G01X631890Y39370D02*
G03X635827Y43307I0J3937D01*
G01X631890Y39370D02*
G03X635827Y43307I0J3937D01*
G01X643701Y169256D02*
G03X635827I-3937J0D01*
G01X643701D02*
G03X635827I-3937J0D01*
G01Y161417D02*
Y1925197D01*
G01Y161417D02*
Y1807087D01*
G01Y199965D02*
G03X643701I3937J0D01*
G01X635827D02*
G03X643701I3937J0D01*
G01Y436186D02*
G03X635827I-3937J0D01*
G01X643701D02*
G03X635827I-3937J0D01*
G01Y466894D02*
G03X643701I3937J0D01*
G01X635827D02*
G03X643701I3937J0D01*
G01Y703115D02*
G03X635827I-3937J0D01*
G01Y733823D02*
G03X643701I3937J0D01*
G01Y703115D02*
G03X635827I-3937J0D01*
G01Y733823D02*
G03X643701I3937J0D01*
G01X635827Y997603D02*
G03X643701I3937J0D01*
G01Y970832D02*
G03X635827I-3937J0D01*
G01Y997603D02*
G03X643701I3937J0D01*
G01Y970832D02*
G03X635827I-3937J0D01*
G01Y1265320D02*
G03X643701I3937J0D01*
G01Y1234611D02*
G03X635827I-3937J0D01*
G01Y1265320D02*
G03X643701I3937J0D01*
G01Y1234611D02*
G03X635827I-3937J0D01*
G01X643701Y1501541D02*
G03X635827I-3937J0D01*
G01X643701D02*
G03X635827I-3937J0D01*
G01Y1532249D02*
G03X643701I3937J0D01*
G01X635827D02*
G03X643701I3937J0D01*
G01Y1768470D02*
G03X635827I-3937J0D01*
G01X643701D02*
G03X635827I-3937J0D01*
G01Y1799178D02*
G03X643701I3937J0D01*
G01X635827D02*
G03X643701I3937J0D01*
G01X635827Y1915647D02*
Y1974929D01*
G01Y1925197D02*
G03X631890Y1929134I-3937J0D01*
G01X635827Y1925197D02*
G03X631890Y1929134I-3937J0D01*
G01X635827Y1974929D02*
X634615Y1990677D01*
G01X650689Y1948819D02*
G03I-6988J0D01*
G01D02*
G03I-6988J0D01*
G01D02*
G03I-6988J0D01*
G01X643701Y1929134D02*
G03X635827Y1937008I-7874J0D01*
G01X627953D02*
X635827D01*
G01X627953D02*
X635827D01*
G01X610399Y1940497D02*
X594399D01*
G01Y1956497D02*
Y1940497D01*
G01X610399Y1956497D02*
X594399D01*
G01X610399Y1940497D02*
Y1956497D01*
G01X604899Y1950997D02*
X599899D01*
G01Y1945997D02*
X604899D01*
G01Y1950997D02*
Y1945997D01*
G01X599899D02*
Y1950997D01*
G01X602399D02*
Y1945997D01*
G01X604899Y1948497D02*
X599899D01*
G01X627953Y1937008D02*
G03Y1929134I0J-3937D01*
G01X597244D02*
G03Y1937008I0J3937D01*
G01X627953D02*
G03Y1929134I0J-3937D01*
G01X597244D02*
G03Y1937008I0J3937D01*
G01X632239Y2007820D02*
X631482Y2008389D01*
X631103Y2009051D01*
X630977Y2009809D01*
X631229Y2010756D01*
X631861Y2011419D01*
X632618Y2011608D01*
X633376Y2011513D01*
X634007Y2011134D01*
X635270Y2009241D01*
X636153Y2008389D01*
X637416Y2007820D01*
X638552Y2007631D01*
Y2011608D01*
G01X632239Y2015395D02*
X631482Y2015964D01*
X631103Y2016626D01*
X630977Y2017384D01*
X631229Y2018331D01*
X631861Y2018994D01*
X632618Y2019183D01*
X633376Y2019088D01*
X634007Y2018709D01*
X635270Y2016816D01*
X636153Y2015964D01*
X637416Y2015395D01*
X638552Y2015206D01*
Y2019183D01*
G01X637037Y2022686D02*
X637921Y2023254D01*
X638426Y2024012D01*
X638552Y2024864D01*
X638426Y2025622D01*
X637795Y2026379D01*
X637037Y2026853D01*
X636280Y2026947D01*
X635396Y2026758D01*
X634765Y2026095D01*
X634512Y2025432D01*
Y2024580D01*
G01Y2025432D02*
X634133Y2026000D01*
X633502Y2026474D01*
X632745Y2026663D01*
X631987Y2026474D01*
X631356Y2026000D01*
X630977Y2025148D01*
X631103Y2024296D01*
X631608Y2023444D01*
G01X638804Y2032344D02*
X638678Y2032155D01*
X638426D01*
X638300Y2032344D01*
X638426Y2032534D01*
X638678D01*
X638804Y2032344D01*
G01X630977Y2039919D02*
X631229Y2039162D01*
X631861Y2038594D01*
X632618Y2038215D01*
X633628Y2037931D01*
X634765Y2037836D01*
X635901Y2037931D01*
X636911Y2038215D01*
X637668Y2038594D01*
X638300Y2039162D01*
X638552Y2039919D01*
X638300Y2040677D01*
X637668Y2041245D01*
X636911Y2041624D01*
X635901Y2041908D01*
X634765Y2042003D01*
X633628Y2041908D01*
X632618Y2041624D01*
X631861Y2041245D01*
X631229Y2040677D01*
X630977Y2039919D01*
G01Y2047494D02*
X631229Y2046737D01*
X631861Y2046169D01*
X632618Y2045790D01*
X633628Y2045506D01*
X634765Y2045411D01*
X635901Y2045506D01*
X636911Y2045790D01*
X637668Y2046169D01*
X638300Y2046737D01*
X638552Y2047494D01*
X638300Y2048252D01*
X637668Y2048820D01*
X636911Y2049199D01*
X635901Y2049483D01*
X634765Y2049578D01*
X633628Y2049483D01*
X632618Y2049199D01*
X631861Y2048820D01*
X631229Y2048252D01*
X630977Y2047494D01*
G01X634615Y1990677D02*
Y2006425D01*
G01X678381Y-75501D02*
X679376Y-74175D01*
X680228Y-73418D01*
X681364Y-73039D01*
X682358Y-73418D01*
X683068Y-74175D01*
X683637Y-75311D01*
X683779Y-76637D01*
X683637Y-77773D01*
X683068Y-78910D01*
X682216Y-79856D01*
X681222Y-80235D01*
X680086Y-79856D01*
X679092Y-78720D01*
X678523Y-77016D01*
X678381Y-75122D01*
X678665Y-72661D01*
X679092Y-71335D01*
X679802Y-70009D01*
X680796Y-69062D01*
X681790Y-68873D01*
X682784Y-69252D01*
X683495Y-70199D01*
G01X648386Y0D02*
G03X663386Y15000I0J15000D01*
G01Y1953504D02*
Y15000D01*
G01X643701Y169256D02*
Y39370D01*
G01Y436186D02*
Y199965D01*
G01Y703115D02*
Y466894D01*
G01Y970832D02*
Y733823D01*
G01Y1234611D02*
Y997603D01*
G01Y1501541D02*
Y1265320D01*
G01Y1768470D02*
Y1532249D01*
G01Y1929134D02*
Y1799178D01*
G01X663386Y1902405D02*
Y1977587D01*
G01D02*
X663848Y1993335D01*
G01X663386Y1953504D02*
G03X648386Y1968504I-15000J0D01*
G01X661472Y2010478D02*
X660715Y2011047D01*
X660336Y2011709D01*
X660210Y2012467D01*
X660462Y2013414D01*
X661094Y2014077D01*
X661851Y2014266D01*
X662609Y2014171D01*
X663240Y2013792D01*
X664503Y2011899D01*
X665386Y2011047D01*
X666649Y2010478D01*
X667785Y2010289D01*
Y2014266D01*
G01X666270Y2017769D02*
X667154Y2018337D01*
X667659Y2019095D01*
X667785Y2019947D01*
X667659Y2020705D01*
X667028Y2021462D01*
X666270Y2021936D01*
X665513Y2022030D01*
X664629Y2021841D01*
X663998Y2021178D01*
X663745Y2020515D01*
Y2019663D01*
G01Y2020515D02*
X663366Y2021083D01*
X662735Y2021557D01*
X661978Y2021746D01*
X661220Y2021557D01*
X660589Y2021083D01*
X660210Y2020231D01*
X660336Y2019379D01*
X660841Y2018527D01*
G01X660210Y2027427D02*
X660462Y2026670D01*
X661094Y2026102D01*
X661851Y2025723D01*
X662861Y2025439D01*
X663998Y2025344D01*
X665134Y2025439D01*
X666144Y2025723D01*
X666901Y2026102D01*
X667533Y2026670D01*
X667785Y2027427D01*
X667533Y2028185D01*
X666901Y2028753D01*
X666144Y2029132D01*
X665134Y2029416D01*
X663998Y2029511D01*
X662861Y2029416D01*
X661851Y2029132D01*
X661094Y2028753D01*
X660462Y2028185D01*
X660210Y2027427D01*
G01X668037Y2035002D02*
X667911Y2034813D01*
X667659D01*
X667533Y2035002D01*
X667659Y2035192D01*
X667911D01*
X668037Y2035002D01*
G01X660210Y2042577D02*
X660462Y2041820D01*
X661094Y2041252D01*
X661851Y2040873D01*
X662861Y2040589D01*
X663998Y2040494D01*
X665134Y2040589D01*
X666144Y2040873D01*
X666901Y2041252D01*
X667533Y2041820D01*
X667785Y2042577D01*
X667533Y2043335D01*
X666901Y2043903D01*
X666144Y2044282D01*
X665134Y2044566D01*
X663998Y2044661D01*
X662861Y2044566D01*
X661851Y2044282D01*
X661094Y2043903D01*
X660462Y2043335D01*
X660210Y2042577D01*
G01Y2050152D02*
X660462Y2049395D01*
X661094Y2048827D01*
X661851Y2048448D01*
X662861Y2048164D01*
X663998Y2048069D01*
X665134Y2048164D01*
X666144Y2048448D01*
X666901Y2048827D01*
X667533Y2049395D01*
X667785Y2050152D01*
X667533Y2050910D01*
X666901Y2051478D01*
X666144Y2051857D01*
X665134Y2052141D01*
X663998Y2052236D01*
X662861Y2052141D01*
X661851Y2051857D01*
X661094Y2051478D01*
X660462Y2050910D01*
X660210Y2050152D01*
G01X663848Y1993335D02*
Y2009083D01*
G01X678381Y2102255D02*
X679376Y2103581D01*
X680228Y2104338D01*
X681364Y2104717D01*
X682358Y2104338D01*
X683068Y2103581D01*
X683637Y2102445D01*
X683779Y2101119D01*
X683637Y2099983D01*
X683068Y2098846D01*
X682216Y2097900D01*
X681222Y2097521D01*
X680086Y2097900D01*
X679092Y2099036D01*
X678523Y2100740D01*
X678381Y2102634D01*
X678665Y2105095D01*
X679092Y2106421D01*
X679802Y2107747D01*
X680796Y2108694D01*
X681790Y2108883D01*
X682784Y2108504D01*
X683495Y2107557D01*
G01X790441Y-65085D02*
Y-84022D01*
G01X796412Y2016087D02*
X797062Y2015365D01*
X797820Y2014932D01*
X798794Y2014788D01*
X799768Y2015077D01*
X800526Y2015654D01*
X801068Y2016664D01*
X801176Y2017819D01*
X800959Y2018974D01*
X800418Y2019696D01*
X799660Y2020273D01*
X798902Y2020418D01*
X798144Y2020273D01*
X797170Y2019696D01*
X797495Y2023449D01*
X800418D01*
G01X807455D02*
X806589Y2023160D01*
X805939Y2022439D01*
X805506Y2021573D01*
X805181Y2020418D01*
X805073Y2019118D01*
X805181Y2017819D01*
X805506Y2016664D01*
X805939Y2015798D01*
X806589Y2015077D01*
X807455Y2014788D01*
X808321Y2015077D01*
X808971Y2015798D01*
X809404Y2016664D01*
X809729Y2017819D01*
X809837Y2019118D01*
X809729Y2020418D01*
X809404Y2021573D01*
X808971Y2022439D01*
X808321Y2023160D01*
X807455Y2023449D01*
G01X816116D02*
X815250Y2023160D01*
X814600Y2022439D01*
X814167Y2021573D01*
X813842Y2020418D01*
X813734Y2019118D01*
X813842Y2017819D01*
X814167Y2016664D01*
X814600Y2015798D01*
X815250Y2015077D01*
X816116Y2014788D01*
X816982Y2015077D01*
X817632Y2015798D01*
X818065Y2016664D01*
X818390Y2017819D01*
X818498Y2019118D01*
X818390Y2020418D01*
X818065Y2021573D01*
X817632Y2022439D01*
X816982Y2023160D01*
X816116Y2023449D01*
G01X824777Y2014499D02*
X824560Y2014644D01*
Y2014932D01*
X824777Y2015077D01*
X824994Y2014932D01*
Y2014644D01*
X824777Y2014499D01*
G01X833438Y2023449D02*
X832572Y2023160D01*
X831922Y2022439D01*
X831489Y2021573D01*
X831164Y2020418D01*
X831056Y2019118D01*
X831164Y2017819D01*
X831489Y2016664D01*
X831922Y2015798D01*
X832572Y2015077D01*
X833438Y2014788D01*
X834304Y2015077D01*
X834954Y2015798D01*
X835387Y2016664D01*
X835712Y2017819D01*
X835820Y2019118D01*
X835712Y2020418D01*
X835387Y2021573D01*
X834954Y2022439D01*
X834304Y2023160D01*
X833438Y2023449D01*
G01X842099D02*
X841233Y2023160D01*
X840583Y2022439D01*
X840150Y2021573D01*
X839825Y2020418D01*
X839717Y2019118D01*
X839825Y2017819D01*
X840150Y2016664D01*
X840583Y2015798D01*
X841233Y2015077D01*
X842099Y2014788D01*
X842965Y2015077D01*
X843615Y2015798D01*
X844048Y2016664D01*
X844373Y2017819D01*
X844481Y2019118D01*
X844373Y2020418D01*
X844048Y2021573D01*
X843615Y2022439D01*
X842965Y2023160D01*
X842099Y2023449D01*
G01X790441Y2112671D02*
Y2093734D01*
G01X811261Y54945D02*
X810395Y54656D01*
X809745Y53935D01*
X809312Y53069D01*
X808987Y51914D01*
X808879Y50614D01*
X808987Y49315D01*
X809312Y48160D01*
X809745Y47294D01*
X810395Y46573D01*
X811261Y46284D01*
X812127Y46573D01*
X812777Y47294D01*
X813210Y48160D01*
X813535Y49315D01*
X813643Y50614D01*
X813535Y51914D01*
X813210Y53069D01*
X812777Y53935D01*
X812127Y54656D01*
X811261Y54945D01*
G01X819922Y45995D02*
X819705Y46140D01*
Y46428D01*
X819922Y46573D01*
X820139Y46428D01*
Y46140D01*
X819922Y45995D01*
G01X828583Y54945D02*
X827717Y54656D01*
X827067Y53935D01*
X826634Y53069D01*
X826309Y51914D01*
X826201Y50614D01*
X826309Y49315D01*
X826634Y48160D01*
X827067Y47294D01*
X827717Y46573D01*
X828583Y46284D01*
X829449Y46573D01*
X830099Y47294D01*
X830532Y48160D01*
X830857Y49315D01*
X830965Y50614D01*
X830857Y51914D01*
X830532Y53069D01*
X830099Y53935D01*
X829449Y54656D01*
X828583Y54945D01*
G01X837244D02*
X836378Y54656D01*
X835728Y53935D01*
X835295Y53069D01*
X834970Y51914D01*
X834862Y50614D01*
X834970Y49315D01*
X835295Y48160D01*
X835728Y47294D01*
X836378Y46573D01*
X837244Y46284D01*
X838110Y46573D01*
X838760Y47294D01*
X839193Y48160D01*
X839518Y49315D01*
X839626Y50614D01*
X839518Y51914D01*
X839193Y53069D01*
X838760Y53935D01*
X838110Y54656D01*
X837244Y54945D01*
G01X868969Y44119D02*
X844823D01*
G01X845347Y92898D02*
X846528Y93489D01*
G01X845347Y102898D02*
X846528Y103489D01*
G01X845347Y112898D02*
X846528Y113489D01*
G01X845347Y122898D02*
X846528Y123489D01*
G01X845347Y132898D02*
X846528Y133489D01*
G01Y130969D02*
Y133489D01*
G01Y120969D02*
Y123489D01*
G01Y110969D02*
Y113489D01*
G01Y100969D02*
Y103489D01*
G01Y90969D02*
Y93489D01*
G01X845347Y131560D02*
Y132898D01*
G01Y121560D02*
Y122898D01*
G01Y111560D02*
Y112898D01*
G01Y101560D02*
Y102898D01*
G01Y91560D02*
Y92898D01*
G01Y131560D02*
X846528Y130969D01*
G01X845347Y121560D02*
X846528Y120969D01*
G01X845347Y111560D02*
X846528Y110969D01*
G01X845347Y101560D02*
X846528Y100969D01*
G01X845347Y91560D02*
X846528Y90969D01*
G01X868969Y133489D02*
X846528D01*
G01X868969Y130969D02*
X846528D01*
G01X868969Y123489D02*
X846528D01*
G01X868969Y120969D02*
X846528D01*
G01X868969Y113489D02*
X846528D01*
G01X868969Y110969D02*
X846528D01*
G01X868969Y103489D02*
X846528D01*
G01X868969Y100969D02*
X846528D01*
G01X868969Y93489D02*
X846528D01*
G01X868969Y90969D02*
X846528D01*
G01X845347Y526127D02*
X846528Y526717D01*
G01X845347Y536127D02*
X846528Y536717D01*
G01X845347Y546127D02*
X846528Y546717D01*
G01Y544198D02*
Y546717D01*
G01Y534198D02*
Y536717D01*
G01Y524198D02*
Y526717D01*
G01X845347Y544788D02*
Y546127D01*
G01Y534788D02*
Y536127D01*
G01Y524788D02*
Y526127D01*
G01Y544788D02*
X846528Y544198D01*
G01X845347Y534788D02*
X846528Y534198D01*
G01X845347Y524788D02*
X846528Y524198D01*
G01X868969Y546717D02*
X846528D01*
G01X868969Y544198D02*
X846528D01*
G01X868969Y536717D02*
X846528D01*
G01X868969Y534198D02*
X846528D01*
G01X868969Y526717D02*
X846528D01*
G01X868969Y524198D02*
X846528D01*
G01X845347Y556127D02*
X846528Y556717D01*
G01X845347Y566127D02*
X846528Y566717D01*
G01Y564198D02*
Y566717D01*
G01Y554198D02*
Y556717D01*
G01X845347Y564788D02*
Y566127D01*
G01Y554788D02*
Y556127D01*
G01Y564788D02*
X846528Y564198D01*
G01X845347Y554788D02*
X846528Y554198D01*
G01X868969Y566717D02*
X846528D01*
G01X868969Y564198D02*
X846528D01*
G01X868969Y556717D02*
X846528D01*
G01X868969Y554198D02*
X846528D01*
G01X845347Y785969D02*
X846528Y786560D01*
G01X845347Y795969D02*
X846528Y796560D01*
G01Y794040D02*
Y796560D01*
G01Y784040D02*
Y786560D01*
G01X845347Y794631D02*
Y795969D01*
G01Y784631D02*
Y785969D01*
G01X868969Y796560D02*
X846528D01*
G01X868969Y794040D02*
X846528D01*
G01X868969Y786560D02*
X846528D01*
G01X868969Y784040D02*
X846528D01*
G01X845347Y794631D02*
X846528Y794040D01*
G01X845347Y784631D02*
X846528Y784040D01*
G01X845347Y805969D02*
X846528Y806560D01*
G01X845347Y815969D02*
X846528Y816560D01*
G01X845347Y825969D02*
X846528Y826560D01*
G01Y824040D02*
Y826560D01*
G01Y814040D02*
Y816560D01*
G01Y804040D02*
Y806560D01*
G01X845347Y824631D02*
Y825969D01*
G01Y814631D02*
Y815969D01*
G01Y804631D02*
Y805969D01*
G01Y824631D02*
X846528Y824040D01*
G01X845347Y814631D02*
X846528Y814040D01*
G01X845347Y804631D02*
X846528Y804040D01*
G01X868969Y826560D02*
X846528D01*
G01X868969Y824040D02*
X846528D01*
G01X868969Y816560D02*
X846528D01*
G01X868969Y814040D02*
X846528D01*
G01X868969Y806560D02*
X846528D01*
G01X868969Y804040D02*
X846528D01*
G01X868969Y1262702D02*
X846528D01*
G01X868969Y1260182D02*
X846528D01*
G01X868969Y1252702D02*
X846528D01*
G01X868969Y1250182D02*
X846528D01*
G01X868969Y1242702D02*
X846528D01*
G01X868969Y1240182D02*
X846528D01*
G01X845347Y1260772D02*
X846528Y1260182D01*
G01X845347Y1250772D02*
X846528Y1250182D01*
G01X868969Y1232702D02*
X846528D01*
G01X868969Y1230182D02*
X846528D01*
G01X845347Y1240772D02*
X846528Y1240182D01*
G01X845347Y1230772D02*
X846528Y1230182D01*
G01Y1260182D02*
Y1262702D01*
G01Y1250182D02*
Y1252702D01*
G01Y1240182D02*
Y1242702D01*
G01Y1230182D02*
Y1232702D01*
G01X845347Y1260772D02*
Y1262111D01*
G01Y1250772D02*
Y1252111D01*
G01Y1240772D02*
Y1242111D01*
G01Y1230772D02*
Y1232111D01*
G01D02*
X846528Y1232702D01*
G01X845347Y1242111D02*
X846528Y1242702D01*
G01X845347Y1252111D02*
X846528Y1252702D01*
G01X845347Y1262111D02*
X846528Y1262702D01*
G01X868969Y1272702D02*
X846528D01*
G01X868969Y1270182D02*
X846528D01*
G01X845347Y1270772D02*
X846528Y1270182D01*
G01D02*
Y1272702D01*
G01X845347Y1270772D02*
Y1272111D01*
G01D02*
X846528Y1272702D01*
G01X868969Y1512544D02*
X846528D01*
G01X868969Y1510024D02*
X846528D01*
G01X868969Y1502544D02*
X846528D01*
G01X868969Y1500024D02*
X846528D01*
G01X868969Y1492544D02*
X846528D01*
G01X868969Y1490024D02*
X846528D01*
G01X845347Y1510615D02*
X846528Y1510024D01*
G01X845347Y1500615D02*
X846528Y1500024D01*
G01X845347Y1490615D02*
X846528Y1490024D01*
G01Y1510024D02*
Y1512544D01*
G01Y1500024D02*
Y1502544D01*
G01Y1490024D02*
Y1492544D01*
G01X845347Y1510615D02*
Y1511954D01*
G01Y1500615D02*
Y1501954D01*
G01Y1490615D02*
Y1491954D01*
G01D02*
X846528Y1492544D01*
G01X845347Y1501954D02*
X846528Y1502544D01*
G01X845347Y1511954D02*
X846528Y1512544D01*
G01X868969Y1532544D02*
X846528D01*
G01X868969Y1530024D02*
X846528D01*
G01X868969Y1522544D02*
X846528D01*
G01X868969Y1520024D02*
X846528D01*
G01X845347Y1530615D02*
X846528Y1530024D01*
G01X845347Y1520615D02*
X846528Y1520024D01*
G01Y1530024D02*
Y1532544D01*
G01Y1520024D02*
Y1522544D01*
G01X845347Y1530615D02*
Y1531954D01*
G01Y1520615D02*
Y1521954D01*
G01D02*
X846528Y1522544D01*
G01X845347Y1531954D02*
X846528Y1532544D01*
G01X868969Y1925772D02*
X846528D01*
G01X868969Y1923253D02*
X846528D01*
G01X845347Y1923843D02*
X846528Y1923253D01*
G01D02*
Y1925772D01*
G01X845347Y1923843D02*
Y1925182D01*
G01D02*
X846528Y1925772D01*
G01X868969Y1965772D02*
X846528D01*
G01X868969Y1963253D02*
X846528D01*
G01X868969Y1955772D02*
X846528D01*
G01X868969Y1953253D02*
X846528D01*
G01X868969Y1945772D02*
X846528D01*
G01X868969Y1943253D02*
X846528D01*
G01X868969Y1935772D02*
X846528D01*
G01X868969Y1933253D02*
X846528D01*
G01X845347Y1963843D02*
X846528Y1963253D01*
G01X845347Y1953843D02*
X846528Y1953253D01*
G01X845347Y1943843D02*
X846528Y1943253D01*
G01X845347Y1933843D02*
X846528Y1933253D01*
G01Y1963253D02*
Y1965772D01*
G01Y1953253D02*
Y1955772D01*
G01Y1943253D02*
Y1945772D01*
G01Y1933253D02*
Y1935772D01*
G01X845347Y1963843D02*
Y1965182D01*
G01Y1953843D02*
Y1955182D01*
G01Y1943843D02*
Y1945182D01*
G01Y1933843D02*
Y1935182D01*
G01D02*
X846528Y1935772D01*
G01X845347Y1945182D02*
X846528Y1945772D01*
G01X845347Y1955182D02*
X846528Y1955772D01*
G01X845347Y1965182D02*
X846528Y1965772D01*
G01X900465Y-80235D02*
X900749Y-77773D01*
X901175Y-75690D01*
X901743Y-73797D01*
X902453Y-71714D01*
X903590Y-68873D01*
X897908D01*
G01X858143Y-26315D02*
X858432Y-27181D01*
X859153Y-27831D01*
X860019Y-28264D01*
X861174Y-28589D01*
X862474Y-28697D01*
X863773Y-28589D01*
X864928Y-28264D01*
X865794Y-27831D01*
X866515Y-27181D01*
X866804Y-26315D01*
X866515Y-25449D01*
X865794Y-24799D01*
X864928Y-24366D01*
X863773Y-24041D01*
X862474Y-23933D01*
X861174Y-24041D01*
X860019Y-24366D01*
X859153Y-24799D01*
X858432Y-25449D01*
X858143Y-26315D01*
G01X867093Y-17654D02*
X866948Y-17871D01*
X866660D01*
X866515Y-17654D01*
X866660Y-17437D01*
X866948D01*
X867093Y-17654D01*
G01X858143Y-8993D02*
X858432Y-9859D01*
X859153Y-10509D01*
X860019Y-10942D01*
X861174Y-11267D01*
X862474Y-11375D01*
X863773Y-11267D01*
X864928Y-10942D01*
X865794Y-10509D01*
X866515Y-9859D01*
X866804Y-8993D01*
X866515Y-8127D01*
X865794Y-7477D01*
X864928Y-7044D01*
X863773Y-6719D01*
X862474Y-6611D01*
X861174Y-6719D01*
X860019Y-7044D01*
X859153Y-7477D01*
X858432Y-8127D01*
X858143Y-8993D01*
G01Y-332D02*
X858432Y-1198D01*
X859153Y-1848D01*
X860019Y-2281D01*
X861174Y-2606D01*
X862474Y-2714D01*
X863773Y-2606D01*
X864928Y-2281D01*
X865794Y-1848D01*
X866515Y-1198D01*
X866804Y-332D01*
X866515Y534D01*
X865794Y1184D01*
X864928Y1617D01*
X863773Y1942D01*
X862474Y2050D01*
X861174Y1942D01*
X860019Y1617D01*
X859153Y1184D01*
X858432Y534D01*
X858143Y-332D01*
G01X868969Y44119D02*
Y7247D01*
G01X905977Y68922D02*
G03I-7086J0D01*
G01X868969Y48056D02*
G03X872906Y44119I3937J0D01*
G01X868969Y48056D02*
G03X872906Y44119I3937J0D01*
G01X878969Y87229D02*
Y137229D01*
G01X877788D02*
Y87229D01*
G01X868969D02*
Y137229D01*
G01Y87229D02*
Y137229D01*
G01Y87229D02*
Y137229D01*
G01Y48056D02*
Y87229D01*
G01Y48056D02*
Y87229D01*
G01D02*
X878969D01*
G01X870095Y45300D02*
X922119D01*
G01X933930Y44119D02*
X872906D01*
G01X933930D02*
X872906D01*
G01X882877Y90969D02*
G03Y93489I1998J1260D01*
G01Y100969D02*
G03Y103489I1998J1260D01*
G01Y110969D02*
G03Y113489I1998J1260D01*
G01Y120969D02*
G03Y123489I1998J1260D01*
G01Y130969D02*
G03Y133489I1998J1260D01*
G01Y93489D02*
G03Y90969I1998J-1260D01*
G01Y103489D02*
G03Y100969I1998J-1260D01*
G01Y113489D02*
G03Y110969I1998J-1260D01*
G01Y123489D02*
G03Y120969I1998J-1260D01*
G01Y133489D02*
G03Y130969I1998J-1260D01*
G01X897283Y101461D02*
X897785Y101625D01*
G01X894100Y107038D02*
X893597Y106874D01*
G01X887973Y132201D02*
X887848Y132160D01*
G01Y132406D02*
X887973Y132447D01*
G01X894770Y114256D02*
X895607Y114584D01*
G01X894770Y121638D02*
X895607Y121966D01*
G01X897785Y101625D02*
X898455Y101953D01*
G01X893597Y106874D02*
X892927Y106546D01*
G01X895607Y111139D02*
X895272Y110975D01*
G01X895607Y113764D02*
X895272Y113600D01*
G01X895607Y118521D02*
X895272Y118357D01*
G01X895607Y121146D02*
X895272Y120982D01*
G01X897283Y102281D02*
X898288Y102937D01*
G01X894100Y106218D02*
X893094Y105562D01*
G01X887680Y132283D02*
X887848Y132406D01*
G01X898455Y101953D02*
X898958Y102445D01*
G01X892927Y106546D02*
X892424Y106054D01*
G01X895272Y110975D02*
X895105Y110811D01*
G01X894435Y111304D02*
X894937Y111796D01*
G01X895272Y113600D02*
X895105Y113436D01*
G01X894435Y113928D02*
X894770Y114256D01*
G01X895272Y118357D02*
X895105Y118193D01*
G01X894435Y118685D02*
X894937Y119178D01*
G01X885544Y92898D02*
X886135Y93489D01*
G01X884206Y91560D02*
X883615Y90969D01*
G01X895272Y120982D02*
X895105Y120818D01*
G01X894435Y121310D02*
X894770Y121638D01*
G01X887848Y132160D02*
X887764Y132078D01*
G01X885544Y102898D02*
X886135Y103489D01*
G01X884206Y101560D02*
X883615Y100969D01*
G01X885544Y112898D02*
X886135Y113489D01*
G01X884206Y111560D02*
X883615Y110969D01*
G01X885544Y122898D02*
X886135Y123489D01*
G01X884206Y121560D02*
X883615Y120969D01*
G01X885544Y132898D02*
X886135Y133489D01*
G01X884206Y131560D02*
X883615Y130969D01*
G01X887555Y132119D02*
X887680Y132283D01*
G01X898288Y102937D02*
X898623Y103430D01*
G01X893094Y105562D02*
X892759Y105070D01*
G01X892424Y106054D02*
X891922Y105234D01*
G01X895105Y110811D02*
X894937Y110483D01*
G01X895105Y113436D02*
X894937Y113108D01*
G01X895105Y118193D02*
X894937Y117865D01*
G01X895105Y120818D02*
X894937Y120490D01*
G01X894267Y110811D02*
X894435Y111304D01*
G01X894267Y113436D02*
X894435Y113928D01*
G01X894267Y118193D02*
X894435Y118685D01*
G01X894267Y120818D02*
X894435Y121310D01*
G01X887764Y132078D02*
X887722Y131955D01*
G01X892759Y105070D02*
X892592Y104250D01*
G01X887513Y131914D02*
X887555Y132119D01*
G01X891922Y105234D02*
X891754Y104250D01*
G01X896948Y99985D02*
Y97360D01*
G01X896277D02*
Y99985D01*
G01X895942Y95063D02*
Y90470D01*
G01X894937D02*
Y95063D01*
G01Y99985D02*
Y97360D01*
G01Y110483D02*
Y110155D01*
G01Y113108D02*
Y112616D01*
G01Y117865D02*
Y117537D01*
G01Y120490D02*
Y119998D01*
G01X894267Y120162D02*
Y120818D01*
G01Y117537D02*
Y118193D01*
G01Y115897D02*
Y116717D01*
G01Y112780D02*
Y113436D01*
G01Y110155D02*
Y110811D01*
G01Y108515D02*
Y109335D01*
G01Y97360D02*
Y99985D01*
G01X891754Y95063D02*
Y96048D01*
G01Y89486D02*
Y90470D01*
G01X889481Y131176D02*
Y130930D01*
G01Y133268D02*
Y133021D01*
G01X888602Y131914D02*
Y131176D01*
G01X888350D02*
Y131955D01*
G01X887722D02*
Y131176D01*
G01X887513Y133021D02*
Y133268D01*
G01Y130930D02*
Y131914D01*
G01X886135Y93489D02*
Y90969D01*
G01Y103489D02*
Y100969D01*
G01Y113489D02*
Y110969D01*
G01Y123489D02*
Y120969D01*
G01Y133489D02*
Y130969D01*
G01X885544Y131560D02*
Y132898D01*
G01Y121560D02*
Y122898D01*
G01Y111560D02*
Y112898D01*
G01Y101560D02*
Y102898D01*
G01Y91560D02*
Y92898D01*
G01X884206Y131560D02*
Y132898D01*
G01Y121560D02*
Y122898D01*
G01Y111560D02*
Y112898D01*
G01Y101560D02*
Y102898D01*
G01Y91560D02*
Y92898D01*
G01X883615Y93489D02*
Y90969D01*
G01Y103489D02*
Y100969D01*
G01Y113489D02*
Y110969D01*
G01Y123489D02*
Y120969D01*
G01Y133489D02*
Y130969D01*
G01X882631Y93489D02*
Y90969D01*
G01Y103489D02*
Y100969D01*
G01Y113489D02*
Y110969D01*
G01Y123489D02*
Y120969D01*
G01Y133489D02*
Y130969D01*
G01X868969Y137229D02*
Y258883D01*
G01Y137229D02*
Y258883D01*
G01X891754Y104250D02*
X891922Y103265D01*
G01X888560Y132119D02*
X888602Y131914D01*
G01X892592Y104250D02*
X892759Y103430D01*
G01X894435Y119670D02*
X894267Y120162D01*
G01X894937Y117537D02*
X895105Y117045D01*
G01X894435D02*
X894267Y117537D01*
G01X888350Y131955D02*
X888308Y132078D01*
G01X894435Y112288D02*
X894267Y112780D01*
G01X894937Y110155D02*
X895105Y109663D01*
G01X894435D02*
X894267Y110155D01*
G01X894937Y119998D02*
X895105Y119670D01*
G01X894937Y112616D02*
X895105Y112288D01*
G01X891922Y103265D02*
X892424Y102445D01*
G01X898623Y105070D02*
X898288Y105562D01*
G01X892759Y103430D02*
X893094Y102937D01*
G01X888434Y132283D02*
X888560Y132119D01*
G01X884206Y132898D02*
X883615Y133489D01*
G01X886135Y130969D02*
X885544Y131560D01*
G01X884206Y122898D02*
X883615Y123489D01*
G01X886135Y120969D02*
X885544Y121560D01*
G01X886135Y110969D02*
X885544Y111560D01*
G01X884206Y112898D02*
X883615Y113489D01*
G01X884206Y102898D02*
X883615Y103489D01*
G01X886135Y100969D02*
X885544Y101560D01*
G01X884206Y92898D02*
X883615Y93489D01*
G01X886135Y90969D02*
X885544Y91560D01*
G01X888308Y132078D02*
X888225Y132160D01*
G01X895105Y119670D02*
X895272Y119506D01*
G01X894937Y119178D02*
X894435Y119670D01*
G01X895105Y117045D02*
X895440Y116717D01*
G01X894770D02*
X894435Y117045D01*
G01X895105Y112288D02*
X895272Y112124D01*
G01X894937Y111796D02*
X894435Y112288D01*
G01X898958Y106054D02*
X898455Y106546D01*
G01X895105Y109663D02*
X895440Y109335D01*
G01X894770D02*
X894435Y109663D01*
G01X892424Y102445D02*
X892927Y101953D01*
G01X887848Y133021D02*
X888141Y132775D01*
G01X887806D02*
X887513Y133021D01*
G01X888267Y132406D02*
X888434Y132283D01*
G01X898288Y105562D02*
X897283Y106218D01*
G01X893094Y102937D02*
X894100Y102281D01*
G01X895272Y119506D02*
X895607Y119342D01*
G01X895272Y112124D02*
X895607Y111960D01*
G01X898455Y106546D02*
X897785Y106874D01*
G01X892927Y101953D02*
X893597Y101625D01*
G01X888141Y132447D02*
X888267Y132406D01*
G01X888225Y132160D02*
X888099Y132201D01*
G01X897785Y106874D02*
X897283Y107038D01*
G01X893597Y101625D02*
X894100Y101461D01*
G01X868969Y137229D02*
X878969D01*
G01Y136442D02*
X868969D01*
G01X878969Y135654D02*
X868969D01*
G01X878969Y133489D02*
X877788D01*
G01X886135D02*
X878969D01*
G01X887513Y133268D02*
X889481D01*
G01Y133021D02*
X887848D01*
G01X885544Y132898D02*
X884206D01*
G01X888141Y132775D02*
X887806D01*
G01X887973Y132447D02*
X888141D01*
G01X888099Y132201D02*
X887973D01*
G01X884206Y131560D02*
X885544D01*
G01X887722Y131176D02*
X888350D01*
G01X888602D02*
X889481D01*
G01X878969Y130969D02*
X877788D01*
G01X886135D02*
X878969D01*
G01X889481Y130930D02*
X887513D01*
G01X868969Y128804D02*
X878969D01*
G01X868969Y128017D02*
X878969D01*
G01Y126442D02*
X868969D01*
G01X878969Y125654D02*
X868969D01*
G01X878969Y123489D02*
X877788D01*
G01X886135D02*
X878969D01*
G01X885544Y122898D02*
X884206D01*
G01X895607Y121966D02*
X899628D01*
G01X884206Y121560D02*
X885544D01*
G01X899628Y121146D02*
X895607D01*
G01X878969Y120969D02*
X877788D01*
G01X886135D02*
X878969D01*
G01X895607Y119342D02*
X899628D01*
G01X868969Y118804D02*
X878969D01*
G01X899628Y118521D02*
X895607D01*
G01X868969Y118017D02*
X878969D01*
G01X895440Y116717D02*
X899628D01*
G01X894267D02*
X894770D01*
G01X878969Y116442D02*
X868969D01*
G01X899628Y115897D02*
X894267D01*
G01X878969Y115654D02*
X868969D01*
G01X895607Y114584D02*
X899628D01*
G01Y113764D02*
X895607D01*
G01X878969Y113489D02*
X877788D01*
G01X886135D02*
X878969D01*
G01X885544Y112898D02*
X884206D01*
G01X895105Y106382D02*
X894100Y106218D01*
G01X896277Y102117D02*
X897283Y102281D01*
G01X894937Y107202D02*
X894100Y107038D01*
G01X896445Y101297D02*
X897283Y101461D01*
G01Y107038D02*
X896445Y107202D01*
G01X894100Y101461D02*
X894937Y101297D01*
G01X897283Y106218D02*
X896277Y106382D01*
G01X894100Y102281D02*
X895105Y102117D01*
G01X895607Y111960D02*
X899628D01*
G01X884206Y111560D02*
X885544D01*
G01X899628Y111139D02*
X895607D01*
G01X878969Y110969D02*
X877788D01*
G01X886135D02*
X878969D01*
G01X895440Y109335D02*
X899628D01*
G01X894267D02*
X894770D01*
G01X868969Y108804D02*
X878969D01*
G01X899628Y108515D02*
X894267D01*
G01X868969Y108017D02*
X878969D01*
G01X896445Y107202D02*
X894937D01*
G01X878969Y106442D02*
X868969D01*
G01X896277Y106382D02*
X895105D01*
G01X878969Y105654D02*
X868969D01*
G01X878969Y103489D02*
X877788D01*
G01X886135D02*
X878969D01*
G01X885544Y102898D02*
X884206D01*
G01X895105Y102117D02*
X896277D01*
G01X884206Y101560D02*
X885544D01*
G01X894937Y101297D02*
X896445D01*
G01X878969Y100969D02*
X877788D01*
G01X886135D02*
X878969D01*
G01X896277Y99985D02*
X896948D01*
G01X894267D02*
X894937D01*
G01X868969Y98804D02*
X878969D01*
G01X868969Y98017D02*
X878969D01*
G01X894937Y97360D02*
X894267D01*
G01X896948D02*
X896277D01*
G01X878969Y96442D02*
X868969D01*
G01X891754Y96048D02*
X899628D01*
G01X878969Y95654D02*
X868969D01*
G01X894937Y95063D02*
X891754D01*
G01X899628D02*
X895942D01*
G01X878969Y93489D02*
X877788D01*
G01X886135D02*
X878969D01*
G01X885544Y92898D02*
X884206D01*
G01Y91560D02*
X885544D01*
G01X878969Y90969D02*
X877788D01*
G01X886135D02*
X878969D01*
G01X895942Y90470D02*
X899628D01*
G01X891754D02*
X894937D01*
G01X899628Y89486D02*
X891754D01*
G01X868969Y88804D02*
X878969D01*
G01X868969Y88017D02*
X878969D01*
G01X905977Y155536D02*
G03I-7086J0D01*
G01X912276Y201599D02*
G03I-15748J0D01*
G01X922119Y179158D02*
X868969D01*
G01X904402Y201599D02*
G03I-7874J0D01*
G01X886848Y274001D02*
G03X886258Y273410I1J-591D01*
G01X886489Y256560D02*
G03X887080Y255969I591J0D01*
G01X886489Y261678D02*
G03X885898Y262268I-590J0D01*
G01X880387Y267702D02*
G03X880190Y267505I0J-197D01*
G01Y266166D02*
G03X880387Y265969I197J0D01*
G01Y264001D02*
G03X880190Y263804I0J-197D01*
G01Y262465D02*
G03X880387Y262268I197J0D01*
G01X866017Y271087D02*
G03Y258883I0J-6102D01*
G01X885471Y270064D02*
X882158Y267702D01*
G01X897709Y271442D02*
X899284Y273017D01*
G01X897709Y259867D02*
X899284Y262702D01*
G01X880190Y269276D02*
X883103Y275969D01*
G01X897709Y253410D02*
Y276560D01*
G01X896528Y271997D02*
Y258817D01*
G01X886489Y261678D02*
Y256560D01*
G01X886258Y273410D02*
Y270064D01*
G01X880387Y262268D02*
Y260062D01*
G01Y265969D02*
Y264001D01*
G01X880190Y272465D02*
Y258883D01*
G01Y273015D02*
Y258817D01*
G01X878812Y275418D02*
Y254552D01*
G01X876253Y272465D02*
Y258883D01*
G01X875465Y271875D02*
Y258883D01*
G01X874875Y251796D02*
Y278174D01*
G01X868969Y271087D02*
Y386580D01*
G01Y271087D02*
Y386580D01*
G01Y258883D02*
Y271087D01*
G01Y258883D02*
Y271087D01*
G01X866017Y258883D02*
Y271087D01*
G01X863064Y259654D02*
Y247859D01*
G01Y270316D02*
Y259654D01*
G01Y282111D02*
Y270316D01*
G01X883024Y254001D02*
X880190Y260515D01*
G01X899284Y267268D02*
X897709Y270103D01*
G01X899284Y257032D02*
X897709Y258922D01*
G01X863064Y282111D02*
X905583D01*
G01X874875Y278174D02*
X901646D01*
G01X897709Y276560D02*
X899284D01*
G01X874875Y276166D02*
X899284D01*
G01Y275969D02*
X883103D01*
G01X899284Y275418D02*
X878812D01*
G01X886848Y274001D02*
X899284D01*
G01X880190Y273015D02*
X874875D01*
G01X876253Y272465D02*
X880190D01*
G01X896528Y271997D02*
X880190D01*
G01X875465Y271875D02*
X876253D01*
G01X874875Y271087D02*
X866017D01*
G01X875465D02*
X874875D01*
G01X886258Y270064D02*
X885471D01*
G01X882158Y267702D02*
X880387D01*
G01Y265969D02*
X899284D01*
G01Y264001D02*
X880387D01*
G01Y262268D02*
X885898D01*
G01X874875Y258883D02*
X880190D01*
G01X874875D02*
X866017D01*
G01X880190Y258843D02*
X874875D01*
G01X896528Y258817D02*
X880190D01*
G01X887080Y255969D02*
X899284D01*
G01Y254552D02*
X878812D01*
G01X899284Y254001D02*
X883024D01*
G01X874875Y253804D02*
X899284D01*
G01X897709Y253410D02*
X899284D01*
G01X874875Y251796D02*
X901646D01*
G01X863064Y247859D02*
X905583D01*
G01X886489Y384257D02*
G03X887080Y383666I591J0D01*
G01X886489Y389375D02*
G03X885898Y389965I-590J0D01*
G01X880190Y393863D02*
G03X880387Y393666I197J0D01*
G01Y391698D02*
G03X880190Y391501I0J-197D01*
G01Y390162D02*
G03X880387Y389965I197J0D01*
G01X866017Y398784D02*
G03Y386580I0J-6102D01*
G01X897709Y387564D02*
X899284Y390398D01*
G01X897709Y381107D02*
Y404257D01*
G01X896528Y399694D02*
Y386514D01*
G01X886489Y389375D02*
Y384257D01*
G01X880387Y389965D02*
Y387759D01*
G01Y393666D02*
Y391698D01*
G01X880190Y400712D02*
Y386514D01*
G01Y400162D02*
Y386580D01*
G01X878812Y403115D02*
Y382249D01*
G01X876253Y400162D02*
Y386580D01*
G01X875465Y399572D02*
Y386580D01*
G01X874875Y379493D02*
Y405871D01*
G01X868969Y386580D02*
Y398784D01*
G01Y386580D02*
Y398784D01*
G01X866017Y386580D02*
Y398784D01*
G01X863064Y387351D02*
Y375556D01*
G01Y398013D02*
Y387351D01*
G01X883024Y381698D02*
X880190Y388212D01*
G01X899284Y384729D02*
X897709Y386619D01*
G01X880387Y393666D02*
X899284D01*
G01Y391698D02*
X880387D01*
G01Y389965D02*
X885898D01*
G01X874875Y386580D02*
X880190D01*
G01X874875D02*
X866017D01*
G01X880190Y386540D02*
X874875D01*
G01X896528Y386514D02*
X880190D01*
G01X887080Y383666D02*
X899284D01*
G01Y382249D02*
X878812D01*
G01X899284Y381698D02*
X883024D01*
G01X874875Y381501D02*
X899284D01*
G01X897709Y381107D02*
X899284D01*
G01X874875Y379493D02*
X901646D01*
G01X863064Y375556D02*
X905583D01*
G01X886848Y401698D02*
G03X886258Y401107I1J-591D01*
G01X880387Y395398D02*
G03X880190Y395202I0J-197D01*
G01X885471Y397761D02*
X882158Y395398D01*
G01X897709Y399139D02*
X899284Y400713D01*
G01X880190Y396973D02*
X883103Y403666D01*
G01X886258Y401107D02*
Y397761D01*
G01X868969Y398784D02*
Y520457D01*
G01Y398784D02*
Y520457D01*
G01X863064Y409808D02*
Y398013D01*
G01X899284Y394965D02*
X897709Y397800D01*
G01X863064Y409808D02*
X905583D01*
G01X874875Y405871D02*
X901646D01*
G01X897709Y404257D02*
X899284D01*
G01X874875Y403863D02*
X899284D01*
G01Y403666D02*
X883103D01*
G01X899284Y403115D02*
X878812D01*
G01X886848Y401698D02*
X899284D01*
G01X880190Y400712D02*
X874875D01*
G01X876253Y400162D02*
X880190D01*
G01X896528Y399694D02*
X880190D01*
G01X875465Y399572D02*
X876253D01*
G01X874875Y398784D02*
X866017D01*
G01X875465D02*
X874875D01*
G01X886258Y397761D02*
X885471D01*
G01X882158Y395398D02*
X880387D01*
G01X905977Y502150D02*
G03I-7086J0D01*
G01X868969Y478528D02*
X922119D01*
G01X882877Y524198D02*
G03Y526717I1998J1260D01*
G01Y534198D02*
G03Y536717I1998J1260D01*
G01Y544198D02*
G03Y546717I1998J1260D01*
G01Y526717D02*
G03Y524198I1998J-1260D01*
G01Y536717D02*
G03Y534198I1998J-1260D01*
G01Y546717D02*
G03Y544198I1998J-1260D01*
G01X885544Y526127D02*
X886135Y526717D01*
G01X884206Y524788D02*
X883615Y524198D01*
G01X885544Y536127D02*
X886135Y536717D01*
G01X884206Y534788D02*
X883615Y534198D01*
G01X885544Y546127D02*
X886135Y546717D01*
G01X884206Y544788D02*
X883615Y544198D01*
G01X886135Y526717D02*
Y524198D01*
G01Y536717D02*
Y534198D01*
G01Y546717D02*
Y544198D01*
G01X885544Y544788D02*
Y546127D01*
G01Y534788D02*
Y536127D01*
G01Y524788D02*
Y526127D01*
G01X884206Y544788D02*
Y546127D01*
G01Y534788D02*
Y536127D01*
G01Y524788D02*
Y526127D01*
G01X883615Y526717D02*
Y524198D01*
G01Y536717D02*
Y534198D01*
G01Y546717D02*
Y544198D01*
G01X882631Y526717D02*
Y524198D01*
G01Y536717D02*
Y534198D01*
G01Y546717D02*
Y544198D01*
G01X878969Y520457D02*
Y570457D01*
G01X877788D02*
Y520457D01*
G01X868969D02*
Y570457D01*
G01Y520457D02*
Y570457D01*
G01Y520457D02*
Y570457D01*
G01X884206Y546127D02*
X883615Y546717D01*
G01X886135Y544198D02*
X885544Y544788D01*
G01X884206Y536127D02*
X883615Y536717D01*
G01X886135Y534198D02*
X885544Y534788D01*
G01X884206Y526127D02*
X883615Y526717D01*
G01X886135Y524198D02*
X885544Y524788D01*
G01X878969Y546717D02*
X877788D01*
G01X886135D02*
X878969D01*
G01X885544Y546127D02*
X884206D01*
G01Y544788D02*
X885544D01*
G01X878969Y544198D02*
X877788D01*
G01X886135D02*
X878969D01*
G01X868969Y542032D02*
X878969D01*
G01X868969Y541245D02*
X878969D01*
G01Y539670D02*
X868969D01*
G01X878969Y538883D02*
X868969D01*
G01X878969Y536717D02*
X877788D01*
G01X886135D02*
X878969D01*
G01X885544Y536127D02*
X884206D01*
G01Y534788D02*
X885544D01*
G01X878969Y534198D02*
X877788D01*
G01X886135D02*
X878969D01*
G01X868969Y532032D02*
X878969D01*
G01X868969Y531245D02*
X878969D01*
G01Y529670D02*
X868969D01*
G01X878969Y528883D02*
X868969D01*
G01X878969Y526717D02*
X877788D01*
G01X886135D02*
X878969D01*
G01X885544Y526127D02*
X884206D01*
G01Y524788D02*
X885544D01*
G01X878969Y524198D02*
X877788D01*
G01X886135D02*
X878969D01*
G01X868969Y522032D02*
X878969D01*
G01X868969Y521245D02*
X878969D01*
G01X868969Y520457D02*
X878969D01*
G01X882877Y554198D02*
G03Y556717I1998J1260D01*
G01Y564198D02*
G03Y566717I1998J1260D01*
G01Y556717D02*
G03Y554198I1998J-1260D01*
G01Y566717D02*
G03Y564198I1998J-1260D01*
G01X905977Y588765D02*
G03I-7086J0D01*
G01X887973Y565430D02*
X887848Y565389D01*
G01Y565635D02*
X887973Y565676D01*
G01X887680Y565512D02*
X887848Y565635D01*
G01Y565389D02*
X887764Y565307D01*
G01X885544Y556127D02*
X886135Y556717D01*
G01X884206Y554788D02*
X883615Y554198D01*
G01X885544Y566127D02*
X886135Y566717D01*
G01X884206Y564788D02*
X883615Y564198D01*
G01X887555Y565348D02*
X887680Y565512D01*
G01X887764Y565307D02*
X887722Y565184D01*
G01X887513Y565143D02*
X887555Y565348D01*
G01X889481Y564404D02*
Y564158D01*
G01Y566496D02*
Y566250D01*
G01X888602Y565143D02*
Y564404D01*
G01X888350D02*
Y565184D01*
G01X887722D02*
Y564404D01*
G01X887513Y566250D02*
Y566496D01*
G01Y564158D02*
Y565143D01*
G01X886135Y556717D02*
Y554198D01*
G01Y566717D02*
Y564198D01*
G01X885544Y564788D02*
Y566127D01*
G01Y554788D02*
Y556127D01*
G01X884206Y564788D02*
Y566127D01*
G01Y554788D02*
Y556127D01*
G01X883615Y556717D02*
Y554198D01*
G01Y566717D02*
Y564198D01*
G01X882631Y556717D02*
Y554198D01*
G01Y566717D02*
Y564198D01*
G01X868969Y570457D02*
Y780300D01*
G01Y570457D02*
Y780300D01*
G01X888560Y565348D02*
X888602Y565143D01*
G01X888350Y565184D02*
X888308Y565307D01*
G01X888434Y565512D02*
X888560Y565348D01*
G01X884206Y566127D02*
X883615Y566717D01*
G01X886135Y564198D02*
X885544Y564788D01*
G01X888308Y565307D02*
X888225Y565389D01*
G01X884206Y556127D02*
X883615Y556717D01*
G01X886135Y554198D02*
X885544Y554788D01*
G01X887848Y566250D02*
X888141Y566004D01*
G01X887806D02*
X887513Y566250D01*
G01X888267Y565635D02*
X888434Y565512D01*
G01X888141Y565676D02*
X888267Y565635D01*
G01X888225Y565389D02*
X888099Y565430D01*
G01X868969Y570457D02*
X878969D01*
G01Y569670D02*
X868969D01*
G01X878969Y568883D02*
X868969D01*
G01X878969Y566717D02*
X877788D01*
G01X886135D02*
X878969D01*
G01X887513Y566496D02*
X889481D01*
G01Y566250D02*
X887848D01*
G01X885544Y566127D02*
X884206D01*
G01X888141Y566004D02*
X887806D01*
G01X887973Y565676D02*
X888141D01*
G01X888099Y565430D02*
X887973D01*
G01X884206Y564788D02*
X885544D01*
G01X887722Y564404D02*
X888350D01*
G01X888602D02*
X889481D01*
G01X878969Y564198D02*
X877788D01*
G01X886135D02*
X878969D01*
G01X889481Y564158D02*
X887513D01*
G01X868969Y562032D02*
X878969D01*
G01X868969Y561245D02*
X878969D01*
G01Y559670D02*
X868969D01*
G01X878969Y558883D02*
X868969D01*
G01X878969Y556717D02*
X877788D01*
G01X886135D02*
X878969D01*
G01X885544Y556127D02*
X884206D01*
G01Y554788D02*
X885544D01*
G01X878969Y554198D02*
X877788D01*
G01X886135D02*
X878969D01*
G01X868969Y552032D02*
X878969D01*
G01X868969Y551245D02*
X878969D01*
G01Y549670D02*
X868969D01*
G01X878969Y548883D02*
X868969D01*
G01X922119Y612387D02*
X868969D01*
G01X903418Y674040D02*
G03I-6890J0D01*
G01X912276D02*
G03I-15748J0D01*
G01X868969Y738371D02*
X922119D01*
G01X882877Y784040D02*
G03Y786560I1998J1260D01*
G01Y794040D02*
G03Y796560I1998J1260D01*
G01Y804040D02*
G03Y806560I1998J1260D01*
G01Y786560D02*
G03Y784040I1998J-1260D01*
G01Y796560D02*
G03Y794040I1998J-1260D01*
G01X905977Y761993D02*
G03I-7086J0D01*
G01X899543Y803765D02*
X898538Y803108D01*
G01X885544Y785969D02*
X886135Y786560D01*
G01X884206Y784631D02*
X883615Y784040D01*
G01X885544Y795969D02*
X886135Y796560D01*
G01X884206Y794631D02*
X883615Y794040D01*
G01X898538Y803108D02*
X898203Y802616D01*
G01X897868Y803601D02*
X897365Y802780D01*
G01X898203Y802616D02*
X898035Y801796D01*
G01X897365Y802780D02*
X897198Y801796D01*
G01D02*
X897365Y800812D01*
G01X898035Y801796D02*
X898203Y800976D01*
G01X897198Y792610D02*
Y793594D01*
G01Y787032D02*
Y788017D01*
G01X886135Y786560D02*
Y784040D01*
G01Y796560D02*
Y794040D01*
G01X885544Y794631D02*
Y795969D01*
G01Y784631D02*
Y785969D01*
G01X884206Y794631D02*
Y795969D01*
G01Y784631D02*
Y785969D01*
G01X883615Y786560D02*
Y784040D01*
G01Y796560D02*
Y794040D01*
G01X882631Y786560D02*
Y784040D01*
G01Y796560D02*
Y794040D01*
G01X878969Y780300D02*
Y830300D01*
G01X877788D02*
Y780300D01*
G01X868969D02*
Y830300D01*
G01Y780300D02*
Y830300D01*
G01Y780300D02*
Y830300D01*
G01X897365Y800812D02*
X897868Y799992D01*
G01X898203Y800976D02*
X898538Y800484D01*
G01X884206Y795969D02*
X883615Y796560D01*
G01X886135Y794040D02*
X885544Y794631D01*
G01X884206Y785969D02*
X883615Y786560D01*
G01X886135Y784040D02*
X885544Y784631D01*
G01X897868Y799992D02*
X898370Y799499D01*
G01X898538Y800484D02*
X899543Y799828D01*
G01X898370Y799499D02*
X899041Y799171D01*
G01X868969Y801875D02*
X878969D01*
G01X868969Y801087D02*
X878969D01*
G01Y799513D02*
X868969D01*
G01X878969Y798725D02*
X868969D01*
G01X878969Y796560D02*
X877788D01*
G01X886135D02*
X878969D01*
G01X885544Y795969D02*
X884206D01*
G01Y794631D02*
X885544D01*
G01X878969Y794040D02*
X877788D01*
G01X886135D02*
X878969D01*
G01X897198Y793594D02*
X905072D01*
G01X900381Y792610D02*
X897198D01*
G01X868969Y791875D02*
X878969D01*
G01X868969Y791087D02*
X878969D01*
G01Y789513D02*
X868969D01*
G01X878969Y788725D02*
X868969D01*
G01X897198Y788017D02*
X900381D01*
G01X905072Y787032D02*
X897198D01*
G01X878969Y786560D02*
X877788D01*
G01X886135D02*
X878969D01*
G01X885544Y785969D02*
X884206D01*
G01Y784631D02*
X885544D01*
G01X878969Y784040D02*
X877788D01*
G01X886135D02*
X878969D01*
G01X868969Y781875D02*
X878969D01*
G01X868969Y781087D02*
X878969D01*
G01X868969Y780300D02*
X878969D01*
G01X882877Y814040D02*
G03Y816560I1998J1260D01*
G01Y824040D02*
G03Y826560I1998J1260D01*
G01Y806560D02*
G03Y804040I1998J-1260D01*
G01Y816560D02*
G03Y814040I1998J-1260D01*
G01Y826560D02*
G03Y824040I1998J-1260D01*
G01X905977Y848607D02*
G03I-7086J0D01*
G01X887973Y825272D02*
X887848Y825231D01*
G01Y825477D02*
X887973Y825518D01*
G01X899041Y804421D02*
X898370Y804093D01*
G01X887680Y825354D02*
X887848Y825477D01*
G01X898370Y804093D02*
X897868Y803601D01*
G01X887848Y825231D02*
X887764Y825149D01*
G01X885544Y805969D02*
X886135Y806560D01*
G01X884206Y804631D02*
X883615Y804040D01*
G01X885544Y815969D02*
X886135Y816560D01*
G01X884206Y814631D02*
X883615Y814040D01*
G01X885544Y825969D02*
X886135Y826560D01*
G01X884206Y824631D02*
X883615Y824040D01*
G01X887555Y825190D02*
X887680Y825354D01*
G01X887764Y825149D02*
X887722Y825026D01*
G01X887513Y824985D02*
X887555Y825190D01*
G01X888560D02*
X888602Y824985D01*
G01X889481Y826338D02*
Y826092D01*
G01Y824247D02*
Y824001D01*
G01X888602Y824985D02*
Y824247D01*
G01X888350D02*
Y825026D01*
G01X887722D02*
Y824247D01*
G01X887513Y826092D02*
Y826338D01*
G01Y824001D02*
Y824985D01*
G01X886135Y806560D02*
Y804040D01*
G01Y816560D02*
Y814040D01*
G01Y826560D02*
Y824040D01*
G01X885544Y824631D02*
Y825969D01*
G01Y814631D02*
Y815969D01*
G01Y804631D02*
Y805969D01*
G01X884206Y824631D02*
Y825969D01*
G01Y814631D02*
Y815969D01*
G01Y804631D02*
Y805969D01*
G01X883615Y806560D02*
Y804040D01*
G01Y816560D02*
Y814040D01*
G01Y826560D02*
Y824040D01*
G01X882631Y806560D02*
Y804040D01*
G01Y816560D02*
Y814040D01*
G01Y826560D02*
Y824040D01*
G01X868969Y830300D02*
Y951934D01*
G01Y830300D02*
Y951934D01*
G01X888350Y825026D02*
X888308Y825149D01*
G01X888434Y825354D02*
X888560Y825190D01*
G01X884206Y825969D02*
X883615Y826560D01*
G01X886135Y824040D02*
X885544Y824631D01*
G01X884206Y815969D02*
X883615Y816560D01*
G01X886135Y814040D02*
X885544Y814631D01*
G01X886135Y804040D02*
X885544Y804631D01*
G01X884206Y805969D02*
X883615Y806560D01*
G01X888308Y825149D02*
X888225Y825231D01*
G01X887848Y826092D02*
X888141Y825846D01*
G01X887806D02*
X887513Y826092D01*
G01X888267Y825477D02*
X888434Y825354D01*
G01X888141Y825518D02*
X888267Y825477D01*
G01X888225Y825231D02*
X888099Y825272D01*
G01X868969Y830300D02*
X878969D01*
G01Y829513D02*
X868969D01*
G01X878969Y828725D02*
X868969D01*
G01X878969Y826560D02*
X877788D01*
G01X886135D02*
X878969D01*
G01X887513Y826338D02*
X889481D01*
G01Y826092D02*
X887848D01*
G01X885544Y825969D02*
X884206D01*
G01X888141Y825846D02*
X887806D01*
G01X887973Y825518D02*
X888141D01*
G01X888099Y825272D02*
X887973D01*
G01X884206Y824631D02*
X885544D01*
G01X887722Y824247D02*
X888350D01*
G01X888602D02*
X889481D01*
G01X878969Y824040D02*
X877788D01*
G01X886135D02*
X878969D01*
G01X889481Y824001D02*
X887513D01*
G01X868969Y821875D02*
X878969D01*
G01X868969Y821087D02*
X878969D01*
G01Y819513D02*
X868969D01*
G01X878969Y818725D02*
X868969D01*
G01X878969Y816560D02*
X877788D01*
G01X886135D02*
X878969D01*
G01X885544Y815969D02*
X884206D01*
G01Y814631D02*
X885544D01*
G01X878969Y814040D02*
X877788D01*
G01X886135D02*
X878969D01*
G01X868969Y811875D02*
X878969D01*
G01X868969Y811087D02*
X878969D01*
G01Y809513D02*
X868969D01*
G01X878969Y808725D02*
X868969D01*
G01X878969Y806560D02*
X877788D01*
G01X886135D02*
X878969D01*
G01X885544Y805969D02*
X884206D01*
G01Y804631D02*
X885544D01*
G01X878969Y804040D02*
X877788D01*
G01X886135D02*
X878969D01*
G01X922119Y872229D02*
X868969D01*
G01X886489Y949611D02*
G03X887080Y949020I591J0D01*
G01X886489Y954729D02*
G03X885898Y955320I-591J0D01*
G01X880387Y957052D02*
G03X880190Y956855I0J-197D01*
G01Y955517D02*
G03X880387Y955320I197J0D01*
G01X866017Y964139D02*
G03Y951934I0J-6102D01*
G01X897709Y952918D02*
X899284Y955753D01*
G01X883024Y947052D02*
X880190Y953566D01*
G01X899284Y950083D02*
X897709Y951973D01*
G01X880387Y955320D02*
X885898D01*
G01X874875Y951934D02*
X880190D01*
G01X874875D02*
X866017D01*
G01X880190Y951894D02*
X874875D01*
G01X896528Y951868D02*
X880190D01*
G01X887080Y949020D02*
X899284D01*
G01Y947603D02*
X878812D01*
G01X899284Y947052D02*
X883024D01*
G01X874875Y946855D02*
X899284D01*
G01X897709Y946461D02*
X899284D01*
G01X874875Y944847D02*
X901646D01*
G01X863064Y940910D02*
X905583D01*
G01X897709Y946461D02*
Y969611D01*
G01X896528Y965049D02*
Y951868D01*
G01X886489Y954729D02*
Y949611D01*
G01X880387Y955320D02*
Y953114D01*
G01X880190Y966066D02*
Y951868D01*
G01Y965517D02*
Y951934D01*
G01X878812Y968469D02*
Y947603D01*
G01X876253Y965517D02*
Y951934D01*
G01X875465Y964926D02*
Y951934D01*
G01X874875Y944847D02*
Y971225D01*
G01X868969Y951934D02*
Y964139D01*
G01Y951934D02*
Y964139D01*
G01X866017Y951934D02*
Y964139D01*
G01X863064Y952706D02*
Y940910D01*
G01Y963367D02*
Y952706D01*
G01X886848Y967052D02*
G03X886258Y966461I1J-591D01*
G01X880387Y960753D02*
G03X880190Y960556I0J-197D01*
G01Y959217D02*
G03X880387Y959020I197J0D01*
G01X885471Y963115D02*
X882158Y960753D01*
G01X863064Y975162D02*
X905583D01*
G01X874875Y971225D02*
X901646D01*
G01X897709Y964493D02*
X899284Y966068D01*
G01X880190Y962328D02*
X883103Y969020D01*
G01X899284Y960320D02*
X897709Y963154D01*
G01Y969611D02*
X899284D01*
G01X874875Y969217D02*
X899284D01*
G01Y969020D02*
X883103D01*
G01X899284Y968469D02*
X878812D01*
G01X886848Y967052D02*
X899284D01*
G01X880190Y966066D02*
X874875D01*
G01X876253Y965517D02*
X880190D01*
G01X896528Y965049D02*
X880190D01*
G01X875465Y964926D02*
X876253D01*
G01X874875Y964139D02*
X866017D01*
G01X875465D02*
X874875D01*
G01X886258Y963115D02*
X885471D01*
G01X882158Y960753D02*
X880387D01*
G01Y959020D02*
X899284D01*
G01Y957052D02*
X880387D01*
G01X886258Y966461D02*
Y963115D01*
G01X880387Y959020D02*
Y957052D01*
G01X868969Y964139D02*
Y1092603D01*
G01Y964139D02*
Y1092603D01*
G01X863064Y975162D02*
Y963367D01*
G01X886848Y1107721D02*
G03X886258Y1107131I0J-590D01*
G01X886489Y1090280D02*
G03X887080Y1089690I590J0D01*
G01X886489Y1095398D02*
G03X885898Y1095989I-591J0D01*
G01X880387Y1101422D02*
G03X880190Y1101225I0J-197D01*
G01Y1099887D02*
G03X880387Y1099690I197J0D01*
G01Y1097721D02*
G03X880190Y1097524I0J-197D01*
G01Y1096186D02*
G03X880387Y1095989I197J0D01*
G01X866017Y1104808D02*
G03Y1092603I0J-6103D01*
G01X897709Y1110280D02*
X899284D01*
G01X874875Y1109887D02*
X899284D01*
G01Y1109690D02*
X883103D01*
G01X899284Y1109139D02*
X878812D01*
G01X886848Y1107721D02*
X899284D01*
G01X880190Y1106735D02*
X874875D01*
G01X876253Y1106186D02*
X880190D01*
G01X896528Y1105718D02*
X880190D01*
G01X875465Y1105595D02*
X876253D01*
G01X874875Y1104808D02*
X866017D01*
G01X875465D02*
X874875D01*
G01X886258Y1103784D02*
X885471D01*
G01X882158Y1101422D02*
X880387D01*
G01Y1099690D02*
X899284D01*
G01Y1097721D02*
X880387D01*
G01Y1095989D02*
X885898D01*
G01X874875Y1092603D02*
X880190D01*
G01X874875D02*
X866017D01*
G01X880190Y1092564D02*
X874875D01*
G01X896528Y1092537D02*
X880190D01*
G01X887080Y1089690D02*
X899284D01*
G01Y1088272D02*
X878812D01*
G01X899284Y1087721D02*
X883024D01*
G01X874875Y1087524D02*
X899284D01*
G01X897709Y1087131D02*
X899284D01*
G01X874875Y1085517D02*
X901646D01*
G01X863064Y1081580D02*
X905583D01*
G01X883024Y1087721D02*
X880190Y1094235D01*
G01X899284Y1100989D02*
X897709Y1103824D01*
G01X899284Y1090753D02*
X897709Y1092643D01*
G01X885471Y1103784D02*
X882158Y1101422D01*
G01X897709Y1105162D02*
X899284Y1106737D01*
G01X897709Y1093587D02*
X899284Y1096422D01*
G01X880190Y1102997D02*
X883103Y1109690D01*
G01X897709Y1087131D02*
Y1110280D01*
G01X896528Y1105718D02*
Y1092537D01*
G01X886489Y1095398D02*
Y1090280D01*
G01X886258Y1107131D02*
Y1103784D01*
G01X880387Y1095989D02*
Y1093783D01*
G01Y1099690D02*
Y1097721D01*
G01X880190Y1106186D02*
Y1092603D01*
G01Y1106735D02*
Y1092537D01*
G01X878812Y1109139D02*
Y1088272D01*
G01X876253Y1106186D02*
Y1092603D01*
G01X875465Y1105595D02*
Y1092603D01*
G01X874875Y1085517D02*
Y1111894D01*
G01X868969Y1104808D02*
Y1226442D01*
G01Y1104808D02*
Y1226442D01*
G01Y1092603D02*
Y1104808D01*
G01Y1092603D02*
Y1104808D01*
G01X866017Y1092603D02*
Y1104808D01*
G01X863064Y1093375D02*
Y1081580D01*
G01Y1104036D02*
Y1093375D01*
G01Y1115831D02*
Y1104036D01*
G01Y1115831D02*
X905583D01*
G01X874875Y1111894D02*
X901646D01*
G01X905977Y1208135D02*
G03I-7086J0D01*
G01X868969Y1184513D02*
X922119D01*
G01X882877Y1230182D02*
G03Y1232702I1998J1260D01*
G01Y1240182D02*
G03Y1242702I1998J1260D01*
G01Y1250182D02*
G03Y1252702I1998J1260D01*
G01Y1260182D02*
G03Y1262702I1998J1260D01*
G01Y1232702D02*
G03Y1230182I1998J-1260D01*
G01Y1242702D02*
G03Y1240182I1998J-1260D01*
G01Y1252702D02*
G03Y1250182I1998J-1260D01*
G01Y1262702D02*
G03Y1260182I1998J-1260D01*
G01X878969Y1262702D02*
X877788D01*
G01X886135D02*
X878969D01*
G01X885544Y1262111D02*
X884206D01*
G01Y1260772D02*
X885544D01*
G01X878969Y1260182D02*
X877788D01*
G01X886135D02*
X878969D01*
G01X868969Y1258017D02*
X878969D01*
G01X868969Y1257229D02*
X878969D01*
G01Y1255654D02*
X868969D01*
G01X897624Y1255641D02*
X898127D01*
G01X878969Y1254867D02*
X868969D01*
G01X902985Y1254821D02*
X897624D01*
G01X878969Y1252702D02*
X877788D01*
G01X886135D02*
X878969D01*
G01X885544Y1252111D02*
X884206D01*
G01Y1250772D02*
X885544D01*
G01X878969Y1250182D02*
X877788D01*
G01X886135D02*
X878969D01*
G01X897624Y1248259D02*
X898127D01*
G01X868969Y1248017D02*
X878969D01*
G01X902985Y1247439D02*
X897624D01*
G01X868969Y1247229D02*
X878969D01*
G01X899802Y1246127D02*
X898294D01*
G01X878969Y1245654D02*
X868969D01*
G01X899634Y1245307D02*
X898462D01*
G01X878969Y1244867D02*
X868969D01*
G01X878969Y1242702D02*
X877788D01*
G01X886135D02*
X878969D01*
G01X885544Y1242111D02*
X884206D01*
G01X898462Y1241041D02*
X899634D01*
G01X884206Y1240772D02*
X885544D01*
G01X898294Y1240221D02*
X899802D01*
G01X878969Y1240182D02*
X877788D01*
G01X886135D02*
X878969D01*
G01X897624Y1238909D02*
X898294D01*
G01X868969Y1238017D02*
X878969D01*
G01X868969Y1237229D02*
X878969D01*
G01X898294Y1236284D02*
X897624D01*
G01X878969Y1235654D02*
X868969D01*
G01X898462Y1245307D02*
X897456Y1245143D01*
G01X898294Y1246127D02*
X897456Y1245963D01*
G01X896451Y1241862D02*
X897456Y1241206D01*
G01X896284Y1240877D02*
X896954Y1240549D01*
G01D02*
X897456Y1240385D01*
G01D02*
X898294Y1240221D01*
G01X897456Y1241206D02*
X898462Y1241041D01*
G01X895111Y1234972D02*
X902985D01*
G01X878969Y1234867D02*
X868969D01*
G01X898294Y1233988D02*
X895111D01*
G01X878969Y1232702D02*
X877788D01*
G01X886135D02*
X878969D01*
G01X885544Y1232111D02*
X884206D01*
G01Y1230772D02*
X885544D01*
G01X878969Y1230182D02*
X877788D01*
G01X886135D02*
X878969D01*
G01X895111Y1229394D02*
X898294D01*
G01X902985Y1228410D02*
X895111D01*
G01X868969Y1228017D02*
X878969D01*
G01X868969Y1227229D02*
X878969D01*
G01X868969Y1226442D02*
X878969D01*
G01X884206Y1262111D02*
X883615Y1262702D01*
G01X886135Y1260182D02*
X885544Y1260772D01*
G01X884206Y1252111D02*
X883615Y1252702D01*
G01X886135Y1250182D02*
X885544Y1250772D01*
G01X884206Y1242111D02*
X883615Y1242702D01*
G01X886135Y1240182D02*
X885544Y1240772D01*
G01X886135Y1230182D02*
X885544Y1230772D01*
G01X884206Y1232111D02*
X883615Y1232702D01*
G01X898462Y1258594D02*
X898629Y1258430D01*
G01X898294Y1258102D02*
X897792Y1258594D01*
G01X898462Y1255969D02*
X898797Y1255641D01*
G01X898127D02*
X897792Y1255969D01*
G01X898462Y1251212D02*
X898629Y1251048D01*
G01X898294Y1250720D02*
X897792Y1251212D01*
G01X898462Y1248587D02*
X898797Y1248259D01*
G01X898127D02*
X897792Y1248587D01*
G01X895781Y1241370D02*
X896284Y1240877D01*
G01X897792Y1258594D02*
X897624Y1259086D01*
G01X898294Y1256461D02*
X898462Y1255969D01*
G01X897792D02*
X897624Y1256461D01*
G01X897792Y1251212D02*
X897624Y1251704D01*
G01X898294Y1249080D02*
X898462Y1248587D01*
G01X897792D02*
X897624Y1249080D01*
G01X898294Y1258922D02*
X898462Y1258594D01*
G01X898294Y1251540D02*
X898462Y1251212D01*
G01X895279Y1242190D02*
X895781Y1241370D01*
G01X896116Y1242354D02*
X896451Y1241862D01*
G01X895111Y1243174D02*
X895279Y1242190D01*
G01X895949Y1243174D02*
X896116Y1242354D01*
G01Y1243994D02*
X895949Y1243174D01*
G01X895279Y1244158D02*
X895111Y1243174D01*
G01X898294Y1229394D02*
Y1233988D01*
G01Y1238909D02*
Y1236284D01*
G01Y1249408D02*
Y1249080D01*
G01Y1252032D02*
Y1251540D01*
G01Y1256789D02*
Y1256461D01*
G01Y1259414D02*
Y1258922D01*
G01X897624Y1259086D02*
Y1259742D01*
G01Y1256461D02*
Y1257118D01*
G01Y1254821D02*
Y1255641D01*
G01Y1251704D02*
Y1252360D01*
G01Y1249080D02*
Y1249736D01*
G01Y1247439D02*
Y1248259D01*
G01Y1236284D02*
Y1238909D01*
G01X895111Y1233988D02*
Y1234972D01*
G01Y1228410D02*
Y1229394D01*
G01X886135Y1232702D02*
Y1230182D01*
G01Y1242702D02*
Y1240182D01*
G01Y1252702D02*
Y1250182D01*
G01Y1262702D02*
Y1260182D01*
G01X885544Y1260772D02*
Y1262111D01*
G01Y1250772D02*
Y1252111D01*
G01Y1240772D02*
Y1242111D01*
G01Y1230772D02*
Y1232111D01*
G01X884206Y1260772D02*
Y1262111D01*
G01Y1250772D02*
Y1252111D01*
G01Y1240772D02*
Y1242111D01*
G01Y1230772D02*
Y1232111D01*
G01X883615Y1232702D02*
Y1230182D01*
G01Y1242702D02*
Y1240182D01*
G01Y1252702D02*
Y1250182D01*
G01Y1262702D02*
Y1260182D01*
G01X882631Y1232702D02*
Y1230182D01*
G01Y1242702D02*
Y1240182D01*
G01Y1252702D02*
Y1250182D01*
G01Y1262702D02*
Y1260182D01*
G01X878969Y1226442D02*
Y1276442D01*
G01X877788D02*
Y1226442D01*
G01X868969D02*
Y1276442D01*
G01Y1226442D02*
Y1276442D01*
G01Y1226442D02*
Y1276442D01*
G01X896451Y1244486D02*
X896116Y1243994D01*
G01X895781Y1244978D02*
X895279Y1244158D01*
G01X898462Y1249736D02*
X898294Y1249408D01*
G01X898462Y1252360D02*
X898294Y1252032D01*
G01X898462Y1257118D02*
X898294Y1256789D01*
G01X898462Y1259742D02*
X898294Y1259414D01*
G01X897624Y1249736D02*
X897792Y1250228D01*
G01X897624Y1252360D02*
X897792Y1252852D01*
G01X897624Y1257118D02*
X897792Y1257610D01*
G01X897624Y1259742D02*
X897792Y1260234D01*
G01X897456Y1245963D02*
X896954Y1245799D01*
G01X898127Y1253181D02*
X898964Y1253509D01*
G01X898127Y1260562D02*
X898964Y1260891D01*
G01X896954Y1245799D02*
X896284Y1245471D01*
G01X897456Y1245143D02*
X896451Y1244486D01*
G01X896284Y1245471D02*
X895781Y1244978D01*
G01X898629Y1249900D02*
X898462Y1249736D01*
G01X897792Y1250228D02*
X898294Y1250720D01*
G01X898629Y1252524D02*
X898462Y1252360D01*
G01X897792Y1252852D02*
X898127Y1253181D01*
G01X898629Y1257282D02*
X898462Y1257118D01*
G01X897792Y1257610D02*
X898294Y1258102D01*
G01X898629Y1259906D02*
X898462Y1259742D01*
G01X897792Y1260234D02*
X898127Y1260562D01*
G01X885544Y1232111D02*
X886135Y1232702D01*
G01X884206Y1230772D02*
X883615Y1230182D01*
G01X885544Y1242111D02*
X886135Y1242702D01*
G01X884206Y1240772D02*
X883615Y1240182D01*
G01X885544Y1252111D02*
X886135Y1252702D01*
G01X884206Y1250772D02*
X883615Y1250182D01*
G01X885544Y1262111D02*
X886135Y1262702D01*
G01X884206Y1260772D02*
X883615Y1260182D01*
G01X882877Y1270182D02*
G03Y1272702I1998J1260D01*
G01D02*
G03Y1270182I1998J-1260D01*
G01X905977Y1294749D02*
G03I-7086J0D01*
G01X888141Y1271660D02*
X888267Y1271619D01*
G01X888225Y1271373D02*
X888099Y1271414D01*
G01X868969Y1276442D02*
X878969D01*
G01Y1275654D02*
X868969D01*
G01X878969Y1274867D02*
X868969D01*
G01X878969Y1272702D02*
X877788D01*
G01X886135D02*
X878969D01*
G01X887513Y1272480D02*
X889481D01*
G01Y1272234D02*
X887848D01*
G01X885544Y1272111D02*
X884206D01*
G01X888141Y1271988D02*
X887806D01*
G01X887973Y1271660D02*
X888141D01*
G01X888099Y1271414D02*
X887973D01*
G01X884206Y1270772D02*
X885544D01*
G01X887722Y1270389D02*
X888350D01*
G01X888602D02*
X889481D01*
G01X878969Y1270182D02*
X877788D01*
G01X886135D02*
X878969D01*
G01X889481Y1270143D02*
X887513D01*
G01X868969Y1268017D02*
X878969D01*
G01X868969Y1267229D02*
X878969D01*
G01Y1265654D02*
X868969D01*
G01X878969Y1264867D02*
X868969D01*
G01X888267Y1271619D02*
X888434Y1271496D01*
G01D02*
X888560Y1271332D01*
G01X884206Y1272111D02*
X883615Y1272702D01*
G01X886135Y1270182D02*
X885544Y1270772D01*
G01X888308Y1271291D02*
X888225Y1271373D01*
G01X887848Y1272234D02*
X888141Y1271988D01*
G01X887806D02*
X887513Y1272234D01*
G01X888350Y1271168D02*
X888308Y1271291D01*
G01X888560Y1271332D02*
X888602Y1271127D01*
G01X887513D02*
X887555Y1271332D01*
G01X889481Y1270389D02*
Y1270143D01*
G01Y1272480D02*
Y1272234D01*
G01X888602Y1271127D02*
Y1270389D01*
G01X888350D02*
Y1271168D01*
G01X887722D02*
Y1270389D01*
G01X887513Y1272234D02*
Y1272480D01*
G01Y1270143D02*
Y1271127D01*
G01X886135Y1272702D02*
Y1270182D01*
G01X885544Y1270772D02*
Y1272111D01*
G01X884206Y1270772D02*
Y1272111D01*
G01X883615Y1272702D02*
Y1270182D01*
G01X882631Y1272702D02*
Y1270182D01*
G01X868969Y1276442D02*
Y1486284D01*
G01Y1276442D02*
Y1486284D01*
G01X887764Y1271291D02*
X887722Y1271168D01*
G01X887973Y1271414D02*
X887848Y1271373D01*
G01Y1271619D02*
X887973Y1271660D01*
G01X887680Y1271496D02*
X887848Y1271619D01*
G01Y1271373D02*
X887764Y1271291D01*
G01X885544Y1272111D02*
X886135Y1272702D01*
G01X884206Y1270772D02*
X883615Y1270182D01*
G01X887555Y1271332D02*
X887680Y1271496D01*
G01X922119Y1318371D02*
X868969D01*
G01X893576Y1382702D02*
G03I-6890J0D01*
G01X902434D02*
G03I-15748J0D01*
G01X905977Y1467977D02*
G03I-7086J0D01*
G01X868969Y1444355D02*
X922119D01*
G01X882877Y1490024D02*
G03Y1492544I1998J1260D01*
G01Y1500024D02*
G03Y1502544I1998J1260D01*
G01Y1510024D02*
G03Y1512544I1998J1260D01*
G01Y1520024D02*
G03Y1522544I1998J1260D01*
G01Y1492544D02*
G03Y1490024I1998J-1260D01*
G01Y1502544D02*
G03Y1500024I1998J-1260D01*
G01Y1512544D02*
G03Y1510024I1998J-1260D01*
G01X868969Y1517859D02*
X878969D01*
G01X868969Y1517072D02*
X878969D01*
G01Y1515497D02*
X868969D01*
G01X878969Y1514709D02*
X868969D01*
G01X878969Y1512544D02*
X877788D01*
G01X886135D02*
X878969D01*
G01X885544Y1511954D02*
X884206D01*
G01Y1510615D02*
X885544D01*
G01X878969Y1510024D02*
X877788D01*
G01X886135D02*
X878969D01*
G01X868969Y1507859D02*
X878969D01*
G01X868969Y1507072D02*
X878969D01*
G01Y1505497D02*
X868969D01*
G01X878969Y1504709D02*
X868969D01*
G01X878969Y1502544D02*
X877788D01*
G01X886135D02*
X878969D01*
G01X885544Y1501954D02*
X884206D01*
G01Y1500615D02*
X885544D01*
G01X896709Y1500435D02*
X904583D01*
G01X878969Y1500024D02*
X877788D01*
G01X886135D02*
X878969D01*
G01X898552Y1506013D02*
X899054Y1505849D01*
G01X899892Y1499451D02*
X896709D01*
G01X868969Y1497859D02*
X878969D01*
G01X868969Y1497072D02*
X878969D01*
G01Y1495497D02*
X868969D01*
G01X896709Y1494858D02*
X899892D01*
G01X878969Y1494709D02*
X868969D01*
G01X904583Y1493874D02*
X896709D01*
G01X878969Y1492544D02*
X877788D01*
G01X886135D02*
X878969D01*
G01X885544Y1491954D02*
X884206D01*
G01Y1490615D02*
X885544D01*
G01X878969Y1490024D02*
X877788D01*
G01X886135D02*
X878969D01*
G01X868969Y1487859D02*
X878969D01*
G01X868969Y1487072D02*
X878969D01*
G01X868969Y1486284D02*
X878969D01*
G01X898049Y1507325D02*
X899054Y1506669D01*
G01X897882Y1506341D02*
X898552Y1506013D01*
G01X884206Y1511954D02*
X883615Y1512544D01*
G01X886135Y1510024D02*
X885544Y1510615D01*
G01X884206Y1501954D02*
X883615Y1502544D01*
G01X886135Y1500024D02*
X885544Y1500615D01*
G01X884206Y1491954D02*
X883615Y1492544D01*
G01X886135Y1490024D02*
X885544Y1490615D01*
G01X897379Y1506833D02*
X897882Y1506341D01*
G01X897714Y1507817D02*
X898049Y1507325D01*
G01X896876Y1507653D02*
X897379Y1506833D01*
G01X896709Y1508638D02*
X896876Y1507653D01*
G01X897547Y1508638D02*
X897714Y1507817D01*
G01X896709Y1499451D02*
Y1500435D01*
G01Y1493874D02*
Y1494858D01*
G01X886135Y1492544D02*
Y1490024D01*
G01Y1502544D02*
Y1500024D01*
G01Y1512544D02*
Y1510024D01*
G01X885544Y1510615D02*
Y1511954D01*
G01Y1500615D02*
Y1501954D01*
G01Y1490615D02*
Y1491954D01*
G01X884206Y1510615D02*
Y1511954D01*
G01Y1500615D02*
Y1501954D01*
G01Y1490615D02*
Y1491954D01*
G01X883615Y1492544D02*
Y1490024D01*
G01Y1502544D02*
Y1500024D01*
G01Y1512544D02*
Y1510024D01*
G01X882631Y1492544D02*
Y1490024D01*
G01Y1502544D02*
Y1500024D01*
G01Y1512544D02*
Y1510024D01*
G01X878969Y1486284D02*
Y1536284D01*
G01X877788D02*
Y1486284D01*
G01X868969D02*
Y1536284D01*
G01Y1486284D02*
Y1536284D01*
G01Y1486284D02*
Y1536284D01*
G01X897714Y1509458D02*
X897547Y1508638D01*
G01X896876Y1509622D02*
X896709Y1508638D01*
G01X897379Y1510442D02*
X896876Y1509622D01*
G01X885544Y1491954D02*
X886135Y1492544D01*
G01X884206Y1490615D02*
X883615Y1490024D01*
G01X898049Y1509950D02*
X897714Y1509458D01*
G01X899054Y1510606D02*
X898049Y1509950D01*
G01X897882Y1510934D02*
X897379Y1510442D01*
G01X885544Y1501954D02*
X886135Y1502544D01*
G01X884206Y1500615D02*
X883615Y1500024D01*
G01X885544Y1511954D02*
X886135Y1512544D01*
G01X884206Y1510615D02*
X883615Y1510024D01*
G01X899054Y1511426D02*
X898552Y1511262D01*
G01D02*
X897882Y1510934D01*
G01X905977Y1554591D02*
G03I-7086J0D01*
G01X882877Y1530024D02*
G03Y1532544I1998J1260D01*
G01Y1522544D02*
G03Y1520024I1998J-1260D01*
G01Y1532544D02*
G03Y1530024I1998J-1260D01*
G01X868969Y1536284D02*
X878969D01*
G01Y1535497D02*
X868969D01*
G01X878969Y1534709D02*
X868969D01*
G01X878969Y1532544D02*
X877788D01*
G01X886135D02*
X878969D01*
G01X887513Y1532323D02*
X889481D01*
G01Y1532077D02*
X887848D01*
G01X885544Y1531954D02*
X884206D01*
G01X888141Y1531830D02*
X887806D01*
G01X887973Y1531502D02*
X888141D01*
G01X888099Y1531256D02*
X887973D01*
G01X884206Y1530615D02*
X885544D01*
G01X887722Y1530231D02*
X888350D01*
G01X888602D02*
X889481D01*
G01X878969Y1530024D02*
X877788D01*
G01X886135D02*
X878969D01*
G01X889481Y1529985D02*
X887513D01*
G01X868969Y1527859D02*
X878969D01*
G01X868969Y1527072D02*
X878969D01*
G01Y1525497D02*
X868969D01*
G01X878969Y1524709D02*
X868969D01*
G01X878969Y1522544D02*
X877788D01*
G01X886135D02*
X878969D01*
G01X885544Y1521954D02*
X884206D01*
G01Y1520615D02*
X885544D01*
G01X878969Y1520024D02*
X877788D01*
G01X886135D02*
X878969D01*
G01X888141Y1531502D02*
X888267Y1531461D01*
G01X888225Y1531215D02*
X888099Y1531256D01*
G01X888267Y1531461D02*
X888434Y1531338D01*
G01X884206Y1531954D02*
X883615Y1532544D01*
G01X886135Y1530024D02*
X885544Y1530615D01*
G01X884206Y1521954D02*
X883615Y1522544D01*
G01X886135Y1520024D02*
X885544Y1520615D01*
G01X888308Y1531133D02*
X888225Y1531215D01*
G01X887848Y1532077D02*
X888141Y1531830D01*
G01X887806D02*
X887513Y1532077D01*
G01X888434Y1531338D02*
X888560Y1531174D01*
G01X888350Y1531010D02*
X888308Y1531133D01*
G01X888560Y1531174D02*
X888602Y1530969D01*
G01X889481Y1532323D02*
Y1532077D01*
G01Y1530231D02*
Y1529985D01*
G01X888602Y1530969D02*
Y1530231D01*
G01X888350D02*
Y1531010D01*
G01X887722D02*
Y1530231D01*
G01X887513Y1532077D02*
Y1532323D01*
G01Y1529985D02*
Y1530969D01*
G01X886135Y1522544D02*
Y1520024D01*
G01Y1532544D02*
Y1530024D01*
G01X885544Y1530615D02*
Y1531954D01*
G01Y1520615D02*
Y1521954D01*
G01X884206Y1530615D02*
Y1531954D01*
G01Y1520615D02*
Y1521954D01*
G01X883615Y1522544D02*
Y1520024D01*
G01Y1532544D02*
Y1530024D01*
G01X882631Y1522544D02*
Y1520024D01*
G01Y1532544D02*
Y1530024D01*
G01X868969Y1536284D02*
Y1657957D01*
G01Y1536284D02*
Y1657957D01*
G01X887513Y1530969D02*
X887555Y1531174D01*
G01X887764Y1531133D02*
X887722Y1531010D01*
G01X887555Y1531174D02*
X887680Y1531338D01*
G01D02*
X887848Y1531461D01*
G01Y1531215D02*
X887764Y1531133D01*
G01X885544Y1521954D02*
X886135Y1522544D01*
G01X884206Y1520615D02*
X883615Y1520024D01*
G01X885544Y1531954D02*
X886135Y1532544D01*
G01X884206Y1530615D02*
X883615Y1530024D01*
G01X887973Y1531256D02*
X887848Y1531215D01*
G01Y1531461D02*
X887973Y1531502D01*
G01X922119Y1578213D02*
X868969D01*
G01X886848Y1673076D02*
G03X886258Y1672485I1J-591D01*
G01X886489Y1655635D02*
G03X887080Y1655044I591J0D01*
G01X886489Y1660753D02*
G03X885898Y1661343I-590J0D01*
G01X880387Y1666776D02*
G03X880190Y1666580I0J-197D01*
G01Y1665241D02*
G03X880387Y1665044I197J0D01*
G01Y1663076D02*
G03X880190Y1662879I0J-197D01*
G01Y1661540D02*
G03X880387Y1661343I197J0D01*
G01X866017Y1670162D02*
G03Y1657957I0J-6102D01*
G01X880190Y1672090D02*
X874875D01*
G01X876253Y1671540D02*
X880190D01*
G01X896528Y1671072D02*
X880190D01*
G01X875465Y1670950D02*
X876253D01*
G01X874875Y1670162D02*
X866017D01*
G01X875465D02*
X874875D01*
G01X886258Y1669139D02*
X885471D01*
G01X882158Y1666776D02*
X880387D01*
G01Y1665044D02*
X899284D01*
G01Y1663076D02*
X880387D01*
G01Y1661343D02*
X885898D01*
G01X874875Y1657957D02*
X880190D01*
G01X874875D02*
X866017D01*
G01X880190Y1657918D02*
X874875D01*
G01X896528Y1657892D02*
X880190D01*
G01X887080Y1655044D02*
X899284D01*
G01Y1653627D02*
X878812D01*
G01X899284Y1653076D02*
X883024D01*
G01X874875Y1652879D02*
X899284D01*
G01X897709Y1652485D02*
X899284D01*
G01X874875Y1650871D02*
X901646D01*
G01X863064Y1646934D02*
X905583D01*
G01X899284Y1656107D02*
X897709Y1657997D01*
G01X899284Y1666343D02*
X897709Y1669178D01*
G01X883024Y1653076D02*
X880190Y1659590D01*
G01X897709Y1652485D02*
Y1675635D01*
G01X896528Y1671072D02*
Y1657892D01*
G01X886489Y1660753D02*
Y1655635D01*
G01X886258Y1672485D02*
Y1669139D01*
G01X880387Y1661343D02*
Y1659137D01*
G01Y1665044D02*
Y1663076D01*
G01X880190Y1672090D02*
Y1657892D01*
G01Y1671540D02*
Y1657957D01*
G01X878812Y1674493D02*
Y1653627D01*
G01X876253Y1671540D02*
Y1657957D01*
G01X875465Y1670950D02*
Y1657957D01*
G01X874875Y1650871D02*
Y1677249D01*
G01X868969Y1670162D02*
Y1785654D01*
G01Y1670162D02*
Y1785654D01*
G01Y1657957D02*
Y1670162D01*
G01Y1657957D02*
Y1670162D01*
G01X866017Y1657957D02*
Y1670162D01*
G01X863064Y1658729D02*
Y1646934D01*
G01Y1669391D02*
Y1658729D01*
G01Y1681186D02*
Y1669391D01*
G01X897709Y1658942D02*
X899284Y1661776D01*
G01X880190Y1668351D02*
X883103Y1675044D01*
G01X897709Y1670517D02*
X899284Y1672091D01*
G01X885471Y1669139D02*
X882158Y1666776D01*
G01X863064Y1681186D02*
X905583D01*
G01X874875Y1677249D02*
X901646D01*
G01X897709Y1675635D02*
X899284D01*
G01X874875Y1675241D02*
X899284D01*
G01Y1675044D02*
X883103D01*
G01X899284Y1674493D02*
X878812D01*
G01X886848Y1673076D02*
X899284D01*
G01X863064Y1774631D02*
X905583D01*
G01X863064Y1786426D02*
Y1774631D01*
G01X886848Y1800772D02*
G03X886258Y1800182I0J-590D01*
G01X886489Y1783331D02*
G03X887080Y1782741I591J1D01*
G01X886489Y1788450D02*
G03X885898Y1789040I-591J-1D01*
G01X880387Y1794473D02*
G03X880190Y1794276I0J-197D01*
G01Y1792938D02*
G03X880387Y1792741I197J0D01*
G01Y1790772D02*
G03X880190Y1790576I0J-197D01*
G01Y1789237D02*
G03X880387Y1789040I197J0D01*
G01X866017Y1797859D02*
G03Y1785654I0J-6103D01*
G01X863064Y1808883D02*
X905583D01*
G01X874875Y1804946D02*
X901646D01*
G01X897709Y1803331D02*
X899284D01*
G01X874875Y1802938D02*
X899284D01*
G01Y1802741D02*
X883103D01*
G01X899284Y1802190D02*
X878812D01*
G01X886848Y1800772D02*
X899284D01*
G01X880190Y1799787D02*
X874875D01*
G01X876253Y1799237D02*
X880190D01*
G01X896528Y1798769D02*
X880190D01*
G01X875465Y1798646D02*
X876253D01*
G01X874875Y1797859D02*
X866017D01*
G01X875465D02*
X874875D01*
G01X886258Y1796835D02*
X885471D01*
G01X882158Y1794473D02*
X880387D01*
G01Y1792741D02*
X899284D01*
G01Y1790772D02*
X880387D01*
G01Y1789040D02*
X885898D01*
G01X874875Y1785654D02*
X880190D01*
G01X874875D02*
X866017D01*
G01X880190Y1785615D02*
X874875D01*
G01X896528Y1785588D02*
X880190D01*
G01X887080Y1782741D02*
X899284D01*
G01Y1781324D02*
X878812D01*
G01X899284Y1780772D02*
X883024D01*
G01X874875Y1780576D02*
X899284D01*
G01X897709Y1780182D02*
X899284D01*
G01X874875Y1778568D02*
X901646D01*
G01X899284Y1783804D02*
X897709Y1785694D01*
G01X899284Y1794040D02*
X897709Y1796875D01*
G01X883024Y1780772D02*
X880190Y1787286D01*
G01X897709Y1780182D02*
Y1803331D01*
G01X896528Y1798769D02*
Y1785588D01*
G01X886489Y1788450D02*
Y1783331D01*
G01X886258Y1800182D02*
Y1796835D01*
G01X880387Y1789040D02*
Y1786834D01*
G01Y1792741D02*
Y1790772D01*
G01X880190Y1799237D02*
Y1785654D01*
G01Y1799787D02*
Y1785588D01*
G01X878812Y1802190D02*
Y1781324D01*
G01X876253Y1799237D02*
Y1785654D01*
G01X875465Y1798646D02*
Y1785654D01*
G01X874875Y1778568D02*
Y1804946D01*
G01X868969Y1797859D02*
Y1919513D01*
G01Y1797859D02*
Y1919513D01*
G01Y1785654D02*
Y1797859D01*
G01Y1785654D02*
Y1797859D01*
G01X866017Y1785654D02*
Y1797859D01*
G01X863064Y1797087D02*
Y1786426D01*
G01Y1808883D02*
Y1797087D01*
G01X880190Y1796048D02*
X883103Y1802741D01*
G01X897709Y1786639D02*
X899284Y1789473D01*
G01X897709Y1798213D02*
X899284Y1799788D01*
G01X885471Y1796835D02*
X882158Y1794473D01*
G01X903418Y1855143D02*
G03I-6890J0D01*
G01X912276D02*
G03I-15748J0D01*
G01X882877Y1923253D02*
G03Y1925772I1998J1260D01*
G01D02*
G03Y1923253I1998J-1260D01*
G01X905977Y1901206D02*
G03I-7086J-1D01*
G01X878969Y1927938D02*
X868969D01*
G01X898010Y1927861D02*
X901696D01*
G01X893822D02*
X897005D01*
G01X901696Y1926877D02*
X893822D01*
G01X878969Y1925772D02*
X877788D01*
G01X886135D02*
X878969D01*
G01X885544Y1925182D02*
X884206D01*
G01Y1923843D02*
X885544D01*
G01X878969Y1923253D02*
X877788D01*
G01X886135D02*
X878969D01*
G01X868969Y1921087D02*
X878969D01*
G01X868969Y1920300D02*
X878969D01*
G01X868969Y1919513D02*
X878969D01*
G01X868969Y1877583D02*
X922119D01*
G01X886135Y1923253D02*
X885544Y1923843D01*
G01X884206Y1925182D02*
X883615Y1925772D01*
G01X898010Y1932454D02*
Y1927861D01*
G01X897005D02*
Y1932454D01*
G01X893822Y1926877D02*
Y1927861D01*
G01X886135Y1925772D02*
Y1923253D01*
G01X885544Y1923843D02*
Y1925182D01*
G01X884206Y1923843D02*
Y1925182D01*
G01X883615Y1925772D02*
Y1923253D01*
G01X882631Y1925772D02*
Y1923253D01*
G01X878969Y1919513D02*
Y1969513D01*
G01X877788D02*
Y1919513D01*
G01X868969D02*
Y1969513D01*
G01Y1919513D02*
Y1969513D01*
G01Y1919513D02*
Y1969513D01*
G01X885544Y1925182D02*
X886135Y1925772D01*
G01X884206Y1923843D02*
X883615Y1923253D01*
G01X882877Y1933253D02*
G03Y1935772I1998J1260D01*
G01Y1943253D02*
G03Y1945772I1998J1260D01*
G01Y1953253D02*
G03Y1955772I1998J1260D01*
G01Y1963253D02*
G03Y1965772I1998J1260D01*
G01Y1935772D02*
G03Y1933253I1998J-1260D01*
G01Y1945772D02*
G03Y1943253I1998J-1260D01*
G01Y1955772D02*
G03Y1953253I1998J-1260D01*
G01Y1965772D02*
G03Y1963253I1998J-1260D01*
G01X899350Y1944430D02*
X898513Y1944594D01*
G01X896167Y1938852D02*
X897005Y1938688D01*
G01X899350Y1943609D02*
X898345Y1943773D01*
G01X896167Y1939672D02*
X897172Y1939508D01*
G01X868969Y1969513D02*
X878969D01*
G01Y1968725D02*
X868969D01*
G01X878969Y1967938D02*
X868969D01*
G01X878969Y1965772D02*
X877788D01*
G01X886135D02*
X878969D01*
G01X887513Y1965551D02*
X889481D01*
G01Y1965305D02*
X887848D01*
G01X885544Y1965182D02*
X884206D01*
G01X888141Y1965059D02*
X887806D01*
G01X887973Y1964731D02*
X888141D01*
G01X888099Y1964485D02*
X887973D01*
G01X884206Y1963843D02*
X885544D01*
G01X887722Y1963459D02*
X888350D01*
G01X888602D02*
X889481D01*
G01X878969Y1963253D02*
X877788D01*
G01X886135D02*
X878969D01*
G01X889481Y1963213D02*
X887513D01*
G01X868969Y1961087D02*
X878969D01*
G01X868969Y1960300D02*
X878969D01*
G01X897675Y1959357D02*
X901696D01*
G01X878969Y1958725D02*
X868969D01*
G01X901696Y1958537D02*
X897675D01*
G01X878969Y1957938D02*
X868969D01*
G01X897675Y1956733D02*
X901696D01*
G01Y1955912D02*
X897675D01*
G01X878969Y1955772D02*
X877788D01*
G01X886135D02*
X878969D01*
G01X885544Y1955182D02*
X884206D01*
G01X897507Y1954108D02*
X901696D01*
G01X896335D02*
X896837D01*
G01X884206Y1953843D02*
X885544D01*
G01X901696Y1953288D02*
X896335D01*
G01X878969Y1953253D02*
X877788D01*
G01X886135D02*
X878969D01*
G01X897675Y1951975D02*
X901696D01*
G01Y1951155D02*
X897675D01*
G01X868969Y1951087D02*
X878969D01*
G01X868969Y1950300D02*
X878969D01*
G01X897675Y1949351D02*
X901696D01*
G01X878969Y1948725D02*
X868969D01*
G01X901696Y1948531D02*
X897675D01*
G01X878969Y1947938D02*
X868969D01*
G01X897507Y1946726D02*
X901696D01*
G01X896335D02*
X896837D01*
G01X901696Y1945906D02*
X896335D01*
G01X878969Y1945772D02*
X877788D01*
G01X886135D02*
X878969D01*
G01X885544Y1945182D02*
X884206D01*
G01X898513Y1944594D02*
X897005D01*
G01X884206Y1943843D02*
X885544D01*
G01X898345Y1943773D02*
X897172D01*
G01X878969Y1943253D02*
X877788D01*
G01X886135D02*
X878969D01*
G01X868969Y1941087D02*
X878969D01*
G01X868969Y1940300D02*
X878969D01*
G01X897172Y1939508D02*
X898345D01*
G01X878969Y1938725D02*
X868969D01*
G01X897005Y1938688D02*
X898513D01*
G01X878969Y1937938D02*
X868969D01*
G01X898345Y1937376D02*
X899015D01*
G01X896335D02*
X897005D01*
G01X878969Y1935772D02*
X877788D01*
G01X886135D02*
X878969D01*
G01X885544Y1935182D02*
X884206D01*
G01X899015Y1934751D02*
X898345D01*
G01X897005D02*
X896335D01*
G01X884206Y1933843D02*
X885544D01*
G01X893822Y1933439D02*
X901696D01*
G01X878969Y1933253D02*
X877788D01*
G01X886135D02*
X878969D01*
G01X897005Y1932454D02*
X893822D01*
G01X901696D02*
X898010D01*
G01X868969Y1931087D02*
X878969D01*
G01X868969Y1930300D02*
X878969D01*
G01Y1928725D02*
X868969D01*
G01X897172Y1943773D02*
X896167Y1943609D01*
G01X898345Y1939508D02*
X899350Y1939672D01*
G01X897005Y1944594D02*
X896167Y1944430D01*
G01X898513Y1938688D02*
X899350Y1938852D01*
G01X897340Y1956897D02*
X897675Y1956733D01*
G01X888141Y1964731D02*
X888267Y1964690D01*
G01X888225Y1964444D02*
X888099Y1964485D01*
G01X895665Y1939016D02*
X896167Y1938852D01*
G01X897340Y1949515D02*
X897675Y1949351D01*
G01X894994Y1939344D02*
X895665Y1939016D01*
G01X887848Y1965305D02*
X888141Y1965059D01*
G01X887806D02*
X887513Y1965305D01*
G01X888267Y1964690D02*
X888434Y1964567D01*
G01X895162Y1940328D02*
X896167Y1939672D01*
G01X884206Y1965182D02*
X883615Y1965772D01*
G01X886135Y1963253D02*
X885544Y1963843D01*
G01X897172Y1957061D02*
X897340Y1956897D01*
G01X897005Y1956569D02*
X896502Y1957061D01*
G01X888308Y1964362D02*
X888225Y1964444D01*
G01X897172Y1954436D02*
X897507Y1954108D01*
G01X896837D02*
X896502Y1954436D01*
G01X897172Y1949679D02*
X897340Y1949515D01*
G01X897005Y1949187D02*
X896502Y1949679D01*
G01X897172Y1947054D02*
X897507Y1946726D01*
G01X896837D02*
X896502Y1947054D01*
G01X894492Y1939836D02*
X894994Y1939344D01*
G01X884206Y1955182D02*
X883615Y1955772D01*
G01X886135Y1953253D02*
X885544Y1953843D01*
G01X884206Y1945182D02*
X883615Y1945772D01*
G01X886135Y1943253D02*
X885544Y1943843D01*
G01X884206Y1935182D02*
X883615Y1935772D01*
G01X886135Y1933253D02*
X885544Y1933843D01*
G01X888434Y1964567D02*
X888560Y1964403D01*
G01X893989Y1940657D02*
X894492Y1939836D01*
G01X894827Y1940821D02*
X895162Y1940328D01*
G01X897005Y1957389D02*
X897172Y1957061D01*
G01X897005Y1950007D02*
X897172Y1949679D01*
G01X896502Y1957061D02*
X896335Y1957553D01*
G01X897005Y1954928D02*
X897172Y1954436D01*
G01X896502D02*
X896335Y1954928D01*
G01X896502Y1949679D02*
X896335Y1950171D01*
G01X897005Y1947546D02*
X897172Y1947054D01*
G01X896502D02*
X896335Y1947546D01*
G01X888350Y1964239D02*
X888308Y1964362D01*
G01X893822Y1941641D02*
X893989Y1940657D01*
G01X894659Y1941641D02*
X894827Y1940821D01*
G01X888560Y1964403D02*
X888602Y1964198D01*
G01X898345Y1934751D02*
Y1937376D01*
G01X897005D02*
Y1934751D01*
G01Y1947874D02*
Y1947546D01*
G01Y1950499D02*
Y1950007D01*
G01Y1955256D02*
Y1954928D01*
G01Y1957881D02*
Y1957389D01*
G01X896335Y1957553D02*
Y1958209D01*
G01Y1954928D02*
Y1955584D01*
G01Y1953288D02*
Y1954108D01*
G01Y1950171D02*
Y1950827D01*
G01Y1947546D02*
Y1948203D01*
G01Y1945906D02*
Y1946726D01*
G01Y1934751D02*
Y1937376D01*
G01X893822Y1932454D02*
Y1933439D01*
G01X889481Y1965551D02*
Y1965305D01*
G01Y1963459D02*
Y1963213D01*
G01X888602Y1964198D02*
Y1963459D01*
G01X888350D02*
Y1964239D01*
G01X887722D02*
Y1963459D01*
G01X887513Y1965305D02*
Y1965551D01*
G01Y1963213D02*
Y1964198D01*
G01X886135Y1935772D02*
Y1933253D01*
G01Y1945772D02*
Y1943253D01*
G01Y1955772D02*
Y1953253D01*
G01Y1965772D02*
Y1963253D01*
G01X885544Y1963843D02*
Y1965182D01*
G01Y1953843D02*
Y1955182D01*
G01Y1943843D02*
Y1945182D01*
G01Y1933843D02*
Y1935182D01*
G01X884206Y1963843D02*
Y1965182D01*
G01Y1953843D02*
Y1955182D01*
G01Y1943843D02*
Y1945182D01*
G01Y1933843D02*
Y1935182D01*
G01X883615Y1935772D02*
Y1933253D01*
G01Y1945772D02*
Y1943253D01*
G01Y1955772D02*
Y1953253D01*
G01Y1965772D02*
Y1963253D01*
G01X882631Y1935772D02*
Y1933253D01*
G01Y1945772D02*
Y1943253D01*
G01Y1955772D02*
Y1953253D01*
G01Y1965772D02*
Y1963253D01*
G01X868969Y1969513D02*
Y2008686D01*
G01Y1969513D02*
Y2008686D01*
G01X894827Y1942461D02*
X894659Y1941641D01*
G01X893989Y1942625D02*
X893822Y1941641D01*
G01X887513Y1964198D02*
X887555Y1964403D01*
G01X896335Y1948203D02*
X896502Y1948695D01*
G01X896335Y1950827D02*
X896502Y1951319D01*
G01X896335Y1955584D02*
X896502Y1956077D01*
G01X896335Y1958209D02*
X896502Y1958701D01*
G01X887764Y1964362D02*
X887722Y1964239D01*
G01X897172Y1948203D02*
X897005Y1947874D01*
G01X897172Y1950827D02*
X897005Y1950499D01*
G01X897172Y1955584D02*
X897005Y1955256D01*
G01X897172Y1958209D02*
X897005Y1957881D01*
G01X895162Y1942953D02*
X894827Y1942461D01*
G01X894492Y1943445D02*
X893989Y1942625D01*
G01X887555Y1964403D02*
X887680Y1964567D01*
G01X894994Y1943937D02*
X894492Y1943445D01*
G01X897340Y1948367D02*
X897172Y1948203D01*
G01X896502Y1948695D02*
X897005Y1949187D01*
G01X897340Y1950991D02*
X897172Y1950827D01*
G01X896502Y1951319D02*
X896837Y1951647D01*
G01X897340Y1955748D02*
X897172Y1955584D01*
G01X896502Y1956077D02*
X897005Y1956569D01*
G01X897340Y1958373D02*
X897172Y1958209D01*
G01X896502Y1958701D02*
X896837Y1959029D01*
G01X885544Y1935182D02*
X886135Y1935772D01*
G01X884206Y1933843D02*
X883615Y1933253D01*
G01X885544Y1945182D02*
X886135Y1945772D01*
G01X884206Y1943843D02*
X883615Y1943253D01*
G01X885544Y1955182D02*
X886135Y1955772D01*
G01X884206Y1953843D02*
X883615Y1953253D01*
G01X885544Y1965182D02*
X886135Y1965772D01*
G01X884206Y1963843D02*
X883615Y1963253D01*
G01X887848Y1964444D02*
X887764Y1964362D01*
G01X896167Y1943609D02*
X895162Y1942953D01*
G01X887680Y1964567D02*
X887848Y1964690D01*
G01X896167Y1944430D02*
X895665Y1944266D01*
G01X887973Y1964485D02*
X887848Y1964444D01*
G01Y1964690D02*
X887973Y1964731D01*
G01X896837Y1951647D02*
X897675Y1951975D01*
G01X896837Y1959029D02*
X897675Y1959357D01*
G01X895665Y1944266D02*
X894994Y1943937D01*
G01X897675Y1948531D02*
X897340Y1948367D01*
G01X897675Y1951155D02*
X897340Y1950991D01*
G01X897675Y1955912D02*
X897340Y1955748D01*
G01X897675Y1958537D02*
X897340Y1958373D01*
G01X868969Y2012623D02*
X849678D01*
G01X905977Y1987820D02*
G03I-7086J0D01*
G01X872906Y2012623D02*
G03X868969Y2008686I0J-3937D01*
G01X872906Y2012623D02*
G03X868969Y2008686I0J-3937D01*
G01X872906Y2012623D02*
X933930D01*
G01X872906D02*
X933930D01*
G01X922119Y2011442D02*
X870095D01*
G01X900465Y2097521D02*
X900749Y2099983D01*
X901175Y2102066D01*
X901743Y2103959D01*
X902453Y2106042D01*
X903590Y2108883D01*
X897908D01*
G01X941804Y83489D02*
G03X937867Y79552I0J-3937D01*
G01X941804Y83489D02*
G03X937867Y79552I0J-3937D01*
G01X933930Y44119D02*
G03X937867Y48056I0J3937D01*
G01X933930Y44119D02*
G03X937867Y48056I0J3937D01*
G01X922119Y45300D02*
G03X931961Y55143I0J9842D01*
G01X937867Y79552D02*
Y48056D01*
G01Y79552D02*
Y48056D01*
G01X931961Y55143D02*
Y169316D01*
G01X1071725Y83489D02*
X941804D01*
G01X1071725D02*
X941804D01*
G01X921922Y112229D02*
G03I-5709J0D01*
G01X898958Y102445D02*
X899461Y103265D01*
G01X898623Y103430D02*
X898790Y104250D01*
G01X899461Y103265D02*
X899628Y104250D01*
G01Y90470D02*
Y89486D01*
G01Y96048D02*
Y95063D01*
G01Y111960D02*
Y111139D01*
G01Y109335D02*
Y108515D01*
G01Y114584D02*
Y113764D01*
G01Y116717D02*
Y115897D01*
G01Y119342D02*
Y118521D01*
G01Y121966D02*
Y121146D01*
G01Y104250D02*
X899461Y105234D01*
G01X898790Y104250D02*
X898623Y105070D01*
G01X899461Y105234D02*
X898958Y106054D01*
G01X954580Y183528D02*
G03I-4902J0D01*
G01X955778Y163528D02*
G03I-6100J0D01*
G01X955938D02*
G03I-6260J0D01*
G01X931961Y169316D02*
G03X922119Y179158I-9842J0D01*
G01X948328Y178578D02*
Y188478D01*
G01X938978Y187528D02*
Y349528D01*
G01X935978Y153528D02*
Y383528D01*
G01X934678Y152032D02*
Y385024D01*
G01X948328Y188478D02*
X951028D01*
G01X955478Y187528D02*
X938978D01*
G01X935978Y183528D02*
X963378D01*
G01X951028Y178578D02*
X948328D01*
G01X935978Y153528D02*
X963378D01*
G01X994678Y152032D02*
X934678D01*
G01X951408Y207028D02*
G03X947948I-1730J-1019D01*
G01X951408Y227028D02*
G03X947948I-1730J-1019D01*
G01X947926Y215028D02*
G03X951430I1752J981D01*
G01X947926Y235028D02*
G03X951430I1752J981D01*
G01X947948Y207028D02*
G03X951408I1730J-1019D01*
G01X947948Y227028D02*
G03X951408I1730J-1019D01*
G01X951430Y215028D02*
G03X947926I-1752J981D01*
G01X951430Y235028D02*
G03X947926I-1752J981D01*
G01X948428Y207028D02*
Y205028D01*
G01Y217028D02*
Y215028D01*
G01Y227028D02*
Y225028D01*
G01Y237028D02*
Y235028D01*
G01X947522D02*
Y237028D01*
G01Y225028D02*
Y227028D01*
G01Y215028D02*
Y217028D01*
G01Y205028D02*
Y207028D01*
G01X946908Y227028D02*
Y235028D01*
G01Y207028D02*
Y215028D01*
G01X940978Y198528D02*
Y243528D01*
G01X947522Y237028D02*
X978384D01*
G01X946908Y235028D02*
X982308D01*
G01X946908Y227028D02*
X982308D01*
G01X947522Y225028D02*
X978384D01*
G01X947522Y217028D02*
X978384D01*
G01X946908Y215028D02*
X982308D01*
G01X946908Y207028D02*
X982308D01*
G01X947522Y205028D02*
X978384D01*
G01X938978Y198528D02*
X990378D01*
G01X951686Y268528D02*
G03I-2008J0D01*
G01Y278528D02*
G03I-2008J0D01*
G01Y288528D02*
G03I-2008J0D01*
G01Y248528D02*
G03I-2008J0D01*
G01Y258528D02*
G03I-2008J0D01*
G01X948037Y246888D02*
X948428Y247278D01*
G01X948037Y256888D02*
X948428Y257278D01*
G01X948037Y266888D02*
X948428Y267278D01*
G01X948037Y276888D02*
X948428Y277278D01*
G01X948037Y286888D02*
X948428Y287278D01*
G01X899678Y273410D02*
X899284Y273017D01*
G01X899678Y263410D02*
X899284Y262702D01*
G01X948428Y287278D02*
Y289778D01*
G01Y277278D02*
Y279778D01*
G01Y267278D02*
Y269778D01*
G01Y257278D02*
Y259778D01*
G01Y247278D02*
Y249778D01*
G01X948298Y287148D02*
Y289908D01*
G01Y277148D02*
Y279908D01*
G01Y267148D02*
Y269908D01*
G01Y257148D02*
Y259908D01*
G01Y247148D02*
Y249908D01*
G01X948037Y286888D02*
Y290169D01*
G01Y276888D02*
Y280169D01*
G01Y266888D02*
Y270169D01*
G01Y256888D02*
Y260169D01*
G01Y246888D02*
Y250169D01*
G01X941178Y243528D02*
Y293528D01*
G01X905583Y247859D02*
Y282111D01*
G01X901646Y275969D02*
Y278174D01*
G01Y265969D02*
Y274001D01*
G01Y255969D02*
Y264001D01*
G01Y251796D02*
Y254001D01*
G01Y255133D02*
Y254887D01*
G01X901253Y255969D02*
Y254001D01*
G01Y265969D02*
Y264001D01*
G01Y275969D02*
Y274001D01*
G01X900505Y255969D02*
Y254001D01*
G01Y265969D02*
Y264001D01*
G01Y275969D02*
Y274001D01*
G01X899678Y254887D02*
Y255133D01*
G01X899284Y273017D02*
Y276560D01*
G01Y262702D02*
Y267268D01*
G01Y264001D02*
Y265969D01*
G01Y253410D02*
Y257032D01*
G01Y255969D02*
Y254001D01*
G01Y275969D02*
Y274001D01*
G01Y267268D02*
X899678Y266560D01*
G01X899284Y257032D02*
X899678Y256560D01*
G01X948037Y290169D02*
X948428Y289778D01*
G01X948037Y280169D02*
X948428Y279778D01*
G01X948037Y270169D02*
X948428Y269778D01*
G01X948037Y260169D02*
X948428Y259778D01*
G01X948037Y250169D02*
X948428Y249778D01*
G01X901353Y255379D02*
X901646Y255133D01*
G01X901311D02*
X901253Y255182D01*
G01D02*
X901018Y255379D01*
G01X948037Y290169D02*
X951318D01*
G01X948298Y289908D02*
X951058D01*
G01X948428Y289778D02*
X950928D01*
G01Y287278D02*
X948428D01*
G01X951058Y287148D02*
X948298D01*
G01X951318Y286888D02*
X948037D01*
G01Y280169D02*
X951318D01*
G01X948298Y279908D02*
X951058D01*
G01X948428Y279778D02*
X950928D01*
G01Y277278D02*
X948428D01*
G01X951058Y277148D02*
X948298D01*
G01X951318Y276888D02*
X948037D01*
G01X901646Y276560D02*
X899284D01*
G01Y275969D02*
X901253D01*
G01X901646D02*
X901253D01*
G01D02*
X899284D01*
G01Y274001D02*
X901253D01*
G01X901646D02*
X901253D01*
G01D02*
X899284D01*
G01X901646Y273410D02*
X899678D01*
G01X948037Y270169D02*
X951318D01*
G01X948298Y269908D02*
X951058D01*
G01X948428Y269778D02*
X950928D01*
G01Y267278D02*
X948428D01*
G01X951058Y267148D02*
X948298D01*
G01X951318Y266888D02*
X948037D01*
G01X901646Y266560D02*
X899678D01*
G01X899284Y265969D02*
X901253D01*
G01X901646D02*
X901253D01*
G01D02*
X899284D01*
G01X901253Y264001D02*
X899284D01*
G01X901646D02*
X901253D01*
G01D02*
X899284D01*
G01X901646Y263410D02*
X899678D01*
G01X948037Y260169D02*
X951318D01*
G01X948298Y259908D02*
X951058D01*
G01X948428Y259778D02*
X950928D01*
G01Y257278D02*
X948428D01*
G01X951058Y257148D02*
X948298D01*
G01X951318Y256888D02*
X948037D01*
G01X901646Y256560D02*
X899678D01*
G01X899284Y255969D02*
X901253D01*
G01X901646D02*
X901253D01*
G01D02*
X899284D01*
G01X901253Y255379D02*
X901353D01*
G01X901018D02*
X901253D01*
G01Y255133D02*
X901311D01*
G01X899678D02*
X901253D01*
G01X901646Y254887D02*
X901253D01*
G01D02*
X899678D01*
G01X901253Y254001D02*
X899284D01*
G01X901646D02*
X901253D01*
G01D02*
X899284D01*
G01X901646Y253410D02*
X899284D01*
G01X948037Y250169D02*
X951318D01*
G01X948298Y249908D02*
X951058D01*
G01X948428Y249778D02*
X950928D01*
G01Y247278D02*
X948428D01*
G01X951058Y247148D02*
X948298D01*
G01X951318Y246888D02*
X948037D01*
G01X938982Y243528D02*
X941178D01*
G01X951430Y322029D02*
G03X947926I-1752J-981D01*
G01X947948Y330028D02*
G03X951408I1730J1020D01*
G01X947926Y322029D02*
G03X951430I1752J-981D01*
G01X951408Y330028D02*
G03X947948I-1730J1020D01*
G01X951430Y302029D02*
G03X947926I-1752J-981D01*
G01X947948Y310028D02*
G03X951408I1730J1020D01*
G01X947926Y302029D02*
G03X951430I1752J-981D01*
G01X951408Y310028D02*
G03X947948I-1730J1020D01*
G01X948428Y302028D02*
Y300028D01*
G01Y312028D02*
Y310028D01*
G01Y322028D02*
Y320028D01*
G01Y332028D02*
Y330028D01*
G01X947522D02*
Y332028D01*
G01Y320028D02*
Y322028D01*
G01Y310028D02*
Y312028D01*
G01Y300028D02*
Y302028D01*
G01X946908Y322028D02*
Y330028D01*
G01Y302028D02*
Y310028D01*
G01X940978Y293528D02*
Y338528D01*
G01X938978D02*
X990378D01*
G01X947522Y332028D02*
X978384D01*
G01X946908Y330028D02*
X982308D01*
G01X946908Y322028D02*
X982308D01*
G01X947522Y320028D02*
X978384D01*
G01X947522Y312028D02*
X978384D01*
G01X946908Y310028D02*
X982308D01*
G01X946908Y302028D02*
X982308D01*
G01X947522Y300028D02*
X978384D01*
G01X938982Y293528D02*
X941178D01*
G01X954580Y353528D02*
G03I-4902J0D01*
G01X955778Y373528D02*
G03I-6100J0D01*
G01X955938D02*
G03I-6260J0D01*
G01X899678Y391107D02*
X899284Y390398D01*
G01X948328Y348578D02*
Y358478D01*
G01X905583Y375556D02*
Y409808D01*
G01X901646Y393666D02*
Y401698D01*
G01Y383666D02*
Y391698D01*
G01Y379493D02*
Y381698D01*
G01Y382830D02*
Y382583D01*
G01X901253Y383666D02*
Y381698D01*
G01Y393666D02*
Y391698D01*
G01X900505Y383666D02*
Y381698D01*
G01Y393666D02*
Y391698D01*
G01X899678Y382583D02*
Y382830D01*
G01X899284Y390398D02*
Y394965D01*
G01Y391698D02*
Y393666D01*
G01Y381107D02*
Y384729D01*
G01Y383666D02*
Y381698D01*
G01Y394965D02*
X899678Y394257D01*
G01X899284Y384729D02*
X899678Y384257D01*
G01X901353Y383076D02*
X901646Y382830D01*
G01X901311D02*
X901253Y382879D01*
G01D02*
X901018Y383076D01*
G01X901646Y394257D02*
X899678D01*
G01X899284Y393666D02*
X901253D01*
G01X901646D02*
X901253D01*
G01D02*
X899284D01*
G01X901253Y391698D02*
X899284D01*
G01X901646D02*
X901253D01*
G01D02*
X899284D01*
G01X901646Y391107D02*
X899678D01*
G01X934678Y385024D02*
X994678D01*
G01X901646Y384257D02*
X899678D01*
G01X899284Y383666D02*
X901253D01*
G01X901646D02*
X901253D01*
G01D02*
X899284D01*
G01X963378Y383528D02*
X935978D01*
G01X901253Y383076D02*
X901353D01*
G01X901018D02*
X901253D01*
G01Y382830D02*
X901311D01*
G01X899678D02*
X901253D01*
G01X901646Y382583D02*
X901253D01*
G01D02*
X899678D01*
G01X901253Y381698D02*
X899284D01*
G01X901646D02*
X901253D01*
G01D02*
X899284D01*
G01X901646Y381107D02*
X899284D01*
G01X948328Y358478D02*
X951028D01*
G01X963378Y353528D02*
X935978D01*
G01X938978Y349528D02*
X955478D01*
G01X951028Y348578D02*
X948328D01*
G01X899678Y401107D02*
X899284Y400713D01*
G01X901646Y403666D02*
Y405871D01*
G01X901253Y403666D02*
Y401698D01*
G01X900505Y403666D02*
Y401698D01*
G01X899284Y400713D02*
Y404257D01*
G01Y403666D02*
Y401698D01*
G01X901646Y404257D02*
X899284D01*
G01Y403666D02*
X901253D01*
G01X901646D02*
X901253D01*
G01D02*
X899284D01*
G01Y401698D02*
X901253D01*
G01X901646D02*
X901253D01*
G01D02*
X899284D01*
G01X901646Y401107D02*
X899678D01*
G01X922119Y478528D02*
G03X931961Y488371I0J9842D01*
G01D02*
Y602544D01*
G01X921922Y545457D02*
G03I-5709J0D01*
G01X904262Y538299D02*
X904764Y538463D01*
G01X901079Y543876D02*
X900576Y543712D01*
G01X904764Y538463D02*
X905434Y538791D01*
G01X900576Y543712D02*
X899906Y543384D01*
G01X904262Y539119D02*
X905267Y539775D01*
G01X901079Y543056D02*
X900073Y542400D01*
G01X905434Y538791D02*
X905937Y539283D01*
G01X899906Y543384D02*
X899403Y542892D01*
G01X902251Y547813D02*
X902084Y547649D01*
G01X905267Y539775D02*
X905602Y540267D01*
G01X900073Y542400D02*
X899738Y541908D01*
G01X905937Y539283D02*
X906440Y540103D01*
G01X899403Y542892D02*
X898901Y542072D01*
G01X902084Y547649D02*
X901916Y547321D01*
G01X901246Y547649D02*
X901414Y548141D01*
G01X905602Y540267D02*
X905769Y541087D01*
G01X899738Y541908D02*
X899571Y541087D01*
G01X906440Y540103D02*
X906607Y541087D01*
G01X898901Y542072D02*
X898733Y541087D01*
G01X906607Y527308D02*
Y526324D01*
G01Y532885D02*
Y531901D01*
G01Y546173D02*
Y545352D01*
G01X903927Y536822D02*
Y534198D01*
G01X903256D02*
Y536822D01*
G01X902921Y531901D02*
Y527308D01*
G01X901916D02*
Y531901D01*
G01Y536822D02*
Y534198D01*
G01Y547321D02*
Y546993D01*
G01X901246D02*
Y547649D01*
G01Y545352D02*
Y546173D01*
G01Y534198D02*
Y536822D01*
G01X898733Y531901D02*
Y532885D01*
G01Y526324D02*
Y527308D01*
G01X906607Y541087D02*
X906440Y542072D01*
G01X898733Y541087D02*
X898901Y540103D01*
G01X905769Y541087D02*
X905602Y541908D01*
G01X899571Y541087D02*
X899738Y540267D01*
G01X901916Y546993D02*
X902084Y546501D01*
G01X901414D02*
X901246Y546993D01*
G01X906440Y542072D02*
X905937Y542892D01*
G01X898901Y540103D02*
X899403Y539283D01*
G01X905602Y541908D02*
X905267Y542400D01*
G01X899738Y540267D02*
X900073Y539775D01*
G01X905937Y542892D02*
X905434Y543384D01*
G01X902084Y546501D02*
X902419Y546173D01*
G01X901749D02*
X901414Y546501D01*
G01X899403Y539283D02*
X899906Y538791D01*
G01X905267Y542400D02*
X904262Y543056D01*
G01X900073Y539775D02*
X901079Y539119D01*
G01X905434Y543384D02*
X904764Y543712D01*
G01X899906Y538791D02*
X900576Y538463D01*
G01X904764Y543712D02*
X904262Y543876D01*
G01X900576Y538463D02*
X901079Y538299D01*
G01X904262Y543876D02*
X903424Y544040D01*
G01X901079Y538299D02*
X901916Y538135D01*
G01X904262Y543056D02*
X903256Y543220D01*
G01X901079Y539119D02*
X902084Y538955D01*
G01X902419Y546173D02*
X906607D01*
G01X901246D02*
X901749D01*
G01X906607Y545352D02*
X901246D01*
G01X903424Y544040D02*
X901916D01*
G01X903256Y543220D02*
X902084D01*
G01Y538955D02*
X903256D01*
G01X901916Y538135D02*
X903424D01*
G01X903256Y536822D02*
X903927D01*
G01X901246D02*
X901916D01*
G01Y534198D02*
X901246D01*
G01X903927D02*
X903256D01*
G01X898733Y532885D02*
X906607D01*
G01X901916Y531901D02*
X898733D01*
G01X906607D02*
X902921D01*
G01Y527308D02*
X906607D01*
G01X898733D02*
X901916D01*
G01X906607Y526324D02*
X898733D01*
G01X902084Y543220D02*
X901079Y543056D01*
G01X903256Y538955D02*
X904262Y539119D01*
G01X901916Y544040D02*
X901079Y543876D01*
G01X903424Y538135D02*
X904262Y538299D01*
G01X901749Y551094D02*
X902586Y551422D01*
G01X901749Y558476D02*
X902586Y558804D01*
G01Y547977D02*
X902251Y547813D01*
G01X902586Y550602D02*
X902251Y550438D01*
G01X902586Y555359D02*
X902251Y555195D01*
G01X902586Y557984D02*
X902251Y557820D01*
G01X901414Y548141D02*
X901916Y548633D01*
G01X902251Y550438D02*
X902084Y550274D01*
G01X901414Y550766D02*
X901749Y551094D01*
G01X902251Y555195D02*
X902084Y555031D01*
G01X901414Y555523D02*
X901916Y556015D01*
G01X902251Y557820D02*
X902084Y557656D01*
G01X901414Y558148D02*
X901749Y558476D01*
G01X902084Y550274D02*
X901916Y549946D01*
G01X902084Y555031D02*
X901916Y554703D01*
G01X902084Y557656D02*
X901916Y557328D01*
G01X901246Y550274D02*
X901414Y550766D01*
G01X901246Y555031D02*
X901414Y555523D01*
G01X901246Y557656D02*
X901414Y558148D01*
G01X906607Y548797D02*
Y547977D01*
G01Y551422D02*
Y550602D01*
G01Y553555D02*
Y552734D01*
G01Y556179D02*
Y555359D01*
G01Y558804D02*
Y557984D01*
G01X901916Y549946D02*
Y549454D01*
G01Y554703D02*
Y554375D01*
G01Y557328D02*
Y556835D01*
G01X901246Y556999D02*
Y557656D01*
G01Y554375D02*
Y555031D01*
G01Y552734D02*
Y553555D01*
G01Y549618D02*
Y550274D01*
G01X901414Y556507D02*
X901246Y556999D01*
G01X901916Y554375D02*
X902084Y553883D01*
G01X901414D02*
X901246Y554375D01*
G01X901414Y549125D02*
X901246Y549618D01*
G01X901916Y556835D02*
X902084Y556507D01*
G01X901916Y549454D02*
X902084Y549125D01*
G01Y556507D02*
X902251Y556343D01*
G01X901916Y556015D02*
X901414Y556507D01*
G01X902084Y553883D02*
X902419Y553555D01*
G01X901749D02*
X901414Y553883D01*
G01X902084Y549125D02*
X902251Y548961D01*
G01X901916Y548633D02*
X901414Y549125D01*
G01X902251Y556343D02*
X902586Y556179D01*
G01X902251Y548961D02*
X902586Y548797D01*
G01Y558804D02*
X906607D01*
G01Y557984D02*
X902586D01*
G01Y556179D02*
X906607D01*
G01Y555359D02*
X902586D01*
G01X902419Y553555D02*
X906607D01*
G01X901246D02*
X901749D01*
G01X906607Y552734D02*
X901246D01*
G01X902586Y551422D02*
X906607D01*
G01Y550602D02*
X902586D01*
G01Y548797D02*
X906607D01*
G01Y547977D02*
X902586D01*
G01X931961Y602544D02*
G03X922119Y612387I-9843J0D01*
G01Y738371D02*
G03X931961Y748213I0J9842D01*
G01D02*
Y862387D01*
G01X921922Y805300D02*
G03I-5709J0D01*
G01X902726Y799007D02*
X903229Y799171D01*
G01D02*
X903899Y799499D01*
G01X902726Y799828D02*
X903731Y800484D01*
G01X903899Y799499D02*
X904402Y799992D01*
G01X903731Y800484D02*
X904066Y800976D01*
G01X904402Y799992D02*
X904904Y800812D01*
G01X904066Y800976D02*
X904234Y801796D01*
G01X904904Y800812D02*
X905072Y801796D01*
G01Y788017D02*
Y787032D01*
G01Y793594D02*
Y792610D01*
G01Y801796D02*
X904904Y802780D01*
G01X904234Y801796D02*
X904066Y802616D01*
G01X902391Y797531D02*
Y794906D01*
G01X901721D02*
Y797531D01*
G01X901386Y792610D02*
Y788017D01*
G01X900381D02*
Y792610D01*
G01Y797531D02*
Y794906D01*
G01X899711D02*
Y797531D01*
G01X904904Y802780D02*
X904402Y803601D01*
G01X904066Y802616D02*
X903731Y803108D01*
G01D02*
X902726Y803765D01*
G01X899041Y799171D02*
X899543Y799007D01*
G01D02*
X900381Y798843D01*
G01X899543Y799828D02*
X900548Y799664D01*
G01D02*
X901721D01*
G01X900381Y798843D02*
X901889D01*
G01X901721Y797531D02*
X902391D01*
G01X899711D02*
X900381D01*
G01X902391Y794906D02*
X901721D01*
G01X900381D02*
X899711D01*
G01X905072Y792610D02*
X901386D01*
G01Y788017D02*
X905072D01*
G01X901721Y799664D02*
X902726Y799828D01*
G01X901889Y798843D02*
X902726Y799007D01*
G01X899543Y804585D02*
X899041Y804421D01*
G01X900213Y811803D02*
X901051Y812131D01*
G01X900213Y819184D02*
X901051Y819513D01*
G01Y808686D02*
X900716Y808522D01*
G01X901051Y811310D02*
X900716Y811146D01*
G01X901051Y816068D02*
X900716Y815904D01*
G01X901051Y818692D02*
X900716Y818528D01*
G01Y808522D02*
X900548Y808358D01*
G01X899878Y808850D02*
X900381Y809342D01*
G01X900716Y811146D02*
X900548Y810982D01*
G01X899878Y811475D02*
X900213Y811803D01*
G01X900716Y815904D02*
X900548Y815740D01*
G01X899878Y816232D02*
X900381Y816724D01*
G01X900716Y818528D02*
X900548Y818364D01*
G01X899878Y818856D02*
X900213Y819184D01*
G01X900548Y808358D02*
X900381Y808030D01*
G01X900548Y810982D02*
X900381Y810654D01*
G01X900548Y815740D02*
X900381Y815412D01*
G01X900548Y818364D02*
X900381Y818036D01*
G01X899711Y808358D02*
X899878Y808850D01*
G01X899711Y810982D02*
X899878Y811475D01*
G01X899711Y815740D02*
X899878Y816232D01*
G01X899711Y818364D02*
X899878Y818856D01*
G01X905072Y806881D02*
Y806061D01*
G01Y809506D02*
Y808686D01*
G01Y812131D02*
Y811310D01*
G01Y816888D02*
Y816068D01*
G01Y814263D02*
Y813443D01*
G01Y819513D02*
Y818692D01*
G01X900381Y808030D02*
Y807702D01*
G01Y810654D02*
Y810162D01*
G01Y815412D02*
Y815083D01*
G01Y818036D02*
Y817544D01*
G01X899711Y817708D02*
Y818364D01*
G01Y815083D02*
Y815740D01*
G01Y813443D02*
Y814263D01*
G01Y810326D02*
Y810982D01*
G01Y807702D02*
Y808358D01*
G01Y806061D02*
Y806881D01*
G01X899878Y817216D02*
X899711Y817708D01*
G01X900381Y815083D02*
X900548Y814591D01*
G01X899878D02*
X899711Y815083D01*
G01X899878Y809834D02*
X899711Y810326D01*
G01X900381Y807702D02*
X900548Y807209D01*
G01X899878D02*
X899711Y807702D01*
G01X900381Y817544D02*
X900548Y817216D01*
G01X900381Y810162D02*
X900548Y809834D01*
G01Y817216D02*
X900716Y817052D01*
G01X900381Y816724D02*
X899878Y817216D01*
G01X900548Y814591D02*
X900883Y814263D01*
G01X900213D02*
X899878Y814591D01*
G01X900548Y809834D02*
X900716Y809670D01*
G01X900381Y809342D02*
X899878Y809834D01*
G01X904402Y803601D02*
X903899Y804093D01*
G01X900548Y807209D02*
X900883Y806881D01*
G01X900213D02*
X899878Y807209D01*
G01X900716Y817052D02*
X901051Y816888D01*
G01X900716Y809670D02*
X901051Y809506D01*
G01X903899Y804093D02*
X903229Y804421D01*
G01D02*
X902726Y804585D01*
G01D02*
X901889Y804749D01*
G01X902726Y803765D02*
X901721Y803929D01*
G01X901051Y819513D02*
X905072D01*
G01Y818692D02*
X901051D01*
G01Y816888D02*
X905072D01*
G01Y816068D02*
X901051D01*
G01X900883Y814263D02*
X905072D01*
G01X899711D02*
X900213D01*
G01X905072Y813443D02*
X899711D01*
G01X901051Y812131D02*
X905072D01*
G01Y811310D02*
X901051D01*
G01Y809506D02*
X905072D01*
G01Y808686D02*
X901051D01*
G01X900883Y806881D02*
X905072D01*
G01X899711D02*
X900213D01*
G01X905072Y806061D02*
X899711D01*
G01X901889Y804749D02*
X900381D01*
G01X901721Y803929D02*
X900548D01*
G01D02*
X899543Y803765D01*
G01X900381Y804749D02*
X899543Y804585D01*
G01X931961Y862387D02*
G03X922119Y872229I-9842J0D01*
G01X899678Y956461D02*
X899284Y955753D01*
G01X905583Y940910D02*
Y975162D01*
G01X899284Y950083D02*
X899678Y949611D01*
G01X901353Y948430D02*
X901646Y948184D01*
G01X901311D02*
X901253Y948233D01*
G01D02*
X901018Y948430D01*
G01X901646Y956461D02*
X899678D01*
G01X901646Y949611D02*
X899678D01*
G01X899284Y949020D02*
X901253D01*
G01X901646D02*
X901253D01*
G01D02*
X899284D01*
G01X901253Y948430D02*
X901353D01*
G01X901018D02*
X901253D01*
G01Y948184D02*
X901311D01*
G01X899678D02*
X901253D01*
G01X901646Y947938D02*
X901253D01*
G01D02*
X899678D01*
G01X901253Y947052D02*
X899284D01*
G01X901646D02*
X901253D01*
G01D02*
X899284D01*
G01X901646Y946461D02*
X899284D01*
G01X901646Y949020D02*
Y957052D01*
G01Y944847D02*
Y947052D01*
G01Y948184D02*
Y947938D01*
G01X901253Y949020D02*
Y947052D01*
G01X900505Y949020D02*
Y947052D01*
G01X899678Y947938D02*
Y948184D01*
G01X899284Y955753D02*
Y960320D01*
G01Y946461D02*
Y950083D01*
G01Y949020D02*
Y947052D01*
G01X899678Y966461D02*
X899284Y966068D01*
G01Y960320D02*
X899678Y959611D01*
G01X901646Y969611D02*
X899284D01*
G01Y969020D02*
X901253D01*
G01X901646D02*
X901253D01*
G01D02*
X899284D01*
G01Y967052D02*
X901253D01*
G01X901646D02*
X901253D01*
G01D02*
X899284D01*
G01X901646Y966461D02*
X899678D01*
G01X901646Y959611D02*
X899678D01*
G01X899284Y959020D02*
X901253D01*
G01X901646D02*
X901253D01*
G01D02*
X899284D01*
G01X901253Y957052D02*
X899284D01*
G01X901646D02*
X901253D01*
G01D02*
X899284D01*
G01X901646Y969020D02*
Y971225D01*
G01Y959020D02*
Y967052D01*
G01X901253Y959020D02*
Y957052D01*
G01Y969020D02*
Y967052D01*
G01X900505Y959020D02*
Y957052D01*
G01Y969020D02*
Y967052D01*
G01X899284Y966068D02*
Y969611D01*
G01Y957052D02*
Y959020D01*
G01Y969020D02*
Y967052D01*
G01X901646Y1110280D02*
X899284D01*
G01Y1109690D02*
X901253D01*
G01X901646D02*
X901253D01*
G01D02*
X899284D01*
G01Y1107721D02*
X901253D01*
G01X901646D02*
X901253D01*
G01D02*
X899284D01*
G01X901646Y1107131D02*
X899678D01*
G01X901646Y1100280D02*
X899678D01*
G01X899284Y1099690D02*
X901253D01*
G01X901646D02*
X901253D01*
G01D02*
X899284D01*
G01X901253Y1097721D02*
X899284D01*
G01X901646D02*
X901253D01*
G01D02*
X899284D01*
G01X901646Y1097131D02*
X899678D01*
G01X901646Y1090280D02*
X899678D01*
G01X899284Y1089690D02*
X901253D01*
G01X901646D02*
X901253D01*
G01D02*
X899284D01*
G01X901253Y1089099D02*
X901353D01*
G01X901018D02*
X901253D01*
G01Y1088853D02*
X901311D01*
G01X899678D02*
X901253D01*
G01X901646Y1088607D02*
X901253D01*
G01D02*
X899678D01*
G01X901253Y1087721D02*
X899284D01*
G01X901646D02*
X901253D01*
G01D02*
X899284D01*
G01X901646Y1087131D02*
X899284D01*
G01Y1100989D02*
X899678Y1100280D01*
G01X899284Y1090753D02*
X899678Y1090280D01*
G01X901353Y1089099D02*
X901646Y1088853D01*
G01X901311D02*
X901253Y1088902D01*
G01D02*
X901018Y1089099D01*
G01X905583Y1081580D02*
Y1115831D01*
G01X899678Y1107131D02*
X899284Y1106737D01*
G01X899678Y1097131D02*
X899284Y1096422D01*
G01X901646Y1109690D02*
Y1111894D01*
G01Y1099690D02*
Y1107721D01*
G01Y1089690D02*
Y1097721D01*
G01Y1085517D02*
Y1087721D01*
G01Y1088853D02*
Y1088607D01*
G01X901253Y1089690D02*
Y1087721D01*
G01Y1099690D02*
Y1097721D01*
G01Y1109690D02*
Y1107721D01*
G01X900505Y1089690D02*
Y1087721D01*
G01Y1099690D02*
Y1097721D01*
G01Y1109690D02*
Y1107721D01*
G01X899678Y1088607D02*
Y1088853D01*
G01X899284Y1106737D02*
Y1110280D01*
G01Y1096422D02*
Y1100989D01*
G01Y1097721D02*
Y1099690D01*
G01Y1087131D02*
Y1090753D01*
G01Y1089690D02*
Y1087721D01*
G01Y1109690D02*
Y1107721D01*
G01X922119Y1184513D02*
G03X931961Y1194355I0J9842D01*
G01D02*
Y1308528D01*
G01X921922Y1251442D02*
G03I-5709J0D01*
G01X898964Y1260891D02*
X902985D01*
G01Y1260070D02*
X898964D01*
G01Y1258266D02*
X902985D01*
G01Y1257446D02*
X898964D01*
G01X898797Y1255641D02*
X902985D01*
G01X898964Y1253509D02*
X902985D01*
G01Y1252688D02*
X898964D01*
G01Y1250884D02*
X902985D01*
G01Y1250064D02*
X898964D01*
G01X898797Y1248259D02*
X902985D01*
G01X899634Y1238909D02*
X900305D01*
G01Y1236284D02*
X899634D01*
G01Y1241041D02*
X900640Y1241206D01*
G01X899802Y1240221D02*
X900640Y1240385D01*
G01X901645Y1244486D02*
X900640Y1245143D01*
G01X898629Y1258430D02*
X898964Y1258266D01*
G01X898629Y1251048D02*
X898964Y1250884D01*
G01X901812Y1245471D02*
X901142Y1245799D01*
G01D02*
X900640Y1245963D01*
G01D02*
X899802Y1246127D01*
G01X900640Y1245143D02*
X899634Y1245307D01*
G01X902985Y1233988D02*
X899299D01*
G01Y1229394D02*
X902985D01*
G01X902315Y1244978D02*
X901812Y1245471D01*
G01X902818Y1244158D02*
X902315Y1244978D01*
G01X901980Y1243994D02*
X901645Y1244486D01*
G01X902985Y1243174D02*
X902818Y1244158D01*
G01X902147Y1243174D02*
X901980Y1243994D01*
G01Y1242354D02*
X902147Y1243174D01*
G01X902818Y1242190D02*
X902985Y1243174D01*
G01Y1229394D02*
Y1228410D01*
G01Y1234972D02*
Y1233988D01*
G01Y1250884D02*
Y1250064D01*
G01Y1248259D02*
Y1247439D01*
G01Y1253509D02*
Y1252688D01*
G01Y1255641D02*
Y1254821D01*
G01Y1258266D02*
Y1257446D01*
G01Y1260891D02*
Y1260070D01*
G01X900305Y1238909D02*
Y1236284D01*
G01X899634D02*
Y1238909D01*
G01X899299Y1233988D02*
Y1229394D01*
G01X901645Y1241862D02*
X901980Y1242354D01*
G01X902315Y1241370D02*
X902818Y1242190D01*
G01X900640Y1240385D02*
X901142Y1240549D01*
G01D02*
X901812Y1240877D01*
G01X898964Y1250064D02*
X898629Y1249900D01*
G01X898964Y1252688D02*
X898629Y1252524D01*
G01X898964Y1257446D02*
X898629Y1257282D01*
G01X898964Y1260070D02*
X898629Y1259906D01*
G01X900640Y1241206D02*
X901645Y1241862D01*
G01X901812Y1240877D02*
X902315Y1241370D01*
G01X931961Y1308528D02*
G03X922119Y1318371I-9842J1D01*
G01X941280Y1365576D02*
X939940D01*
G01X945301D02*
X943961D01*
G01X934914Y1362951D02*
X950662D01*
G01X941280Y1360982D02*
X934914D01*
G01X950662D02*
X943291D01*
G01Y1351796D02*
X950662D01*
G01X934914D02*
X941280D01*
G01X950662Y1349828D02*
X934914D01*
G01X1021332Y1318922D02*
X904402D01*
G01X945301Y1370825D02*
Y1365576D01*
G01X943961D02*
Y1370825D01*
G01X943291Y1360982D02*
Y1351796D01*
G01X941280D02*
Y1360982D01*
G01Y1370825D02*
Y1365576D01*
G01X939940D02*
Y1370825D01*
G01X934914Y1360982D02*
Y1362951D01*
G01Y1349828D02*
Y1351796D01*
G01X904402Y1426796D02*
Y1318922D01*
G01X945971Y1384933D02*
X944296Y1385261D01*
G01X945971Y1383292D02*
X943961Y1383620D01*
G01X942621Y1414788D02*
X950662D01*
G01Y1413148D02*
X942621D01*
G01Y1409539D02*
X950662D01*
G01Y1407898D02*
X942621D01*
G01X942286Y1404289D02*
X950662D01*
G01X939940D02*
X940945D01*
G01X950662Y1402649D02*
X939940D01*
G01X942621Y1400024D02*
X950662D01*
G01Y1398384D02*
X942621D01*
G01Y1394775D02*
X950662D01*
G01Y1393135D02*
X942621D01*
G01X942286Y1389526D02*
X950662D01*
G01X939940D02*
X940945D01*
G01X950662Y1387885D02*
X939940D01*
G01X944296Y1385261D02*
X941280D01*
G01X943961Y1383620D02*
X941615D01*
G01Y1375090D02*
X943961D01*
G01X941280Y1373450D02*
X944296D01*
G01X943961Y1370825D02*
X945301D01*
G01X939940D02*
X941280D01*
G01X941615Y1383620D02*
X939605Y1383292D01*
G01X943961Y1375090D02*
X945971Y1375418D01*
G01X941280Y1385261D02*
X939605Y1384933D01*
G01X944296Y1373450D02*
X945971Y1373778D01*
G01X947982Y1381980D02*
X945971Y1383292D01*
G01X937595Y1376730D02*
X939605Y1375418D01*
G01X941951Y1409867D02*
X942621Y1409539D01*
G01X941951Y1395103D02*
X942621Y1394775D01*
G01X948317Y1383948D02*
X946977Y1384604D01*
G01X937260Y1374762D02*
X938600Y1374106D01*
G01X946977Y1384604D02*
X945971Y1384933D01*
G01X938600Y1374106D02*
X939605Y1373778D01*
G01D02*
X941280Y1373450D01*
G01X939605Y1375418D02*
X941615Y1375090D01*
G01Y1410195D02*
X941951Y1409867D01*
G01X941280Y1409211D02*
X940275Y1410195D01*
G01X941615Y1404946D02*
X942286Y1404289D01*
G01X940945D02*
X940275Y1404946D01*
G01X941615Y1395431D02*
X941951Y1395103D01*
G01X941280Y1394447D02*
X940275Y1395431D01*
G01X949322Y1382964D02*
X948317Y1383948D01*
G01X941615Y1390182D02*
X942286Y1389526D01*
G01X940945D02*
X940275Y1390182D01*
G01X936254Y1375746D02*
X937260Y1374762D01*
G01X941280Y1410851D02*
X941615Y1410195D01*
G01X941280Y1396087D02*
X941615Y1395431D01*
G01X950327Y1381324D02*
X949322Y1382964D01*
G01X935249Y1377387D02*
X936254Y1375746D01*
G01X948652Y1380996D02*
X947982Y1381980D01*
G01X936925Y1377715D02*
X937595Y1376730D01*
G01X940275Y1410195D02*
X939940Y1411179D01*
G01X941280Y1405930D02*
X941615Y1404946D01*
G01X940275D02*
X939940Y1405930D01*
G01X940275Y1395431D02*
X939940Y1396415D01*
G01X941280Y1391166D02*
X941615Y1390182D01*
G01X940275D02*
X939940Y1391166D01*
G01X934914Y1379355D02*
X935249Y1377387D01*
G01X948987Y1379355D02*
X948652Y1380996D01*
G01X936590Y1379355D02*
X936925Y1377715D01*
G01X941280Y1391822D02*
Y1391166D01*
G01Y1397072D02*
Y1396087D01*
G01Y1406586D02*
Y1405930D01*
G01Y1411835D02*
Y1410851D01*
G01X939940Y1411179D02*
Y1412492D01*
G01Y1405930D02*
Y1407242D01*
G01Y1402649D02*
Y1404289D01*
G01Y1396415D02*
Y1397728D01*
G01Y1391166D02*
Y1392478D01*
G01Y1387885D02*
Y1389526D01*
G01X948652Y1377715D02*
X948987Y1379355D01*
G01X936925Y1380996D02*
X936590Y1379355D01*
G01X935249Y1381324D02*
X934914Y1379355D01*
G01X941615Y1392478D02*
X941280Y1391822D01*
G01X941615Y1397728D02*
X941280Y1397072D01*
G01X941615Y1407242D02*
X941280Y1406586D01*
G01X939940Y1392478D02*
X940275Y1393463D01*
G01X939940Y1397728D02*
X940275Y1398712D01*
G01X939940Y1407242D02*
X940275Y1408226D01*
G01X939940Y1412492D02*
X940275Y1413476D01*
G01X947982Y1376730D02*
X948652Y1377715D01*
G01X937595Y1381980D02*
X936925Y1380996D01*
G01X949322Y1375746D02*
X950327Y1377387D01*
G01X936254Y1382964D02*
X935249Y1381324D01*
G01X941615Y1412492D02*
X941280Y1411835D01*
G01X946977Y1374106D02*
X948317Y1374762D01*
G01X945971Y1375418D02*
X947982Y1376730D01*
G01X939605Y1383292D02*
X937595Y1381980D01*
G01X948317Y1374762D02*
X949322Y1375746D01*
G01X937260Y1383948D02*
X936254Y1382964D01*
G01X941951Y1392807D02*
X941615Y1392478D01*
G01X940275Y1393463D02*
X941280Y1394447D01*
G01X941951Y1398056D02*
X941615Y1397728D01*
G01X940275Y1398712D02*
X940945Y1399368D01*
G01X941951Y1407570D02*
X941615Y1407242D01*
G01X940275Y1408226D02*
X941280Y1409211D01*
G01X941951Y1412820D02*
X941615Y1412492D01*
G01X940275Y1413476D02*
X940945Y1414132D01*
G01X945971Y1373778D02*
X946977Y1374106D01*
G01X939605Y1384933D02*
X938600Y1384604D01*
G01X940945Y1399368D02*
X942621Y1400024D01*
G01X940945Y1414132D02*
X942621Y1414788D01*
G01X938600Y1384604D02*
X937260Y1383948D01*
G01X942621Y1393135D02*
X941951Y1392807D01*
G01X942621Y1398384D02*
X941951Y1398056D01*
G01X942621Y1407898D02*
X941951Y1407570D01*
G01X942621Y1413148D02*
X941951Y1412820D01*
G01X922119Y1444355D02*
G03X931961Y1454198I0J9842D01*
G01X904402Y1426796D02*
X1021332D01*
G01X931961Y1454198D02*
Y1568371D01*
G01X921922Y1511284D02*
G03I-5709J0D01*
G01X900562Y1518972D02*
X904583D01*
G01Y1518152D02*
X900562D01*
G01Y1516348D02*
X904583D01*
G01Y1515527D02*
X900562D01*
G01X900395Y1513723D02*
X904583D01*
G01X899222D02*
X899725D01*
G01X904583Y1512903D02*
X899222D01*
G01X901400Y1511590D02*
X899892D01*
G01X901232Y1510770D02*
X900060D01*
G01Y1506505D02*
X901232D01*
G01X899892Y1505685D02*
X901400D01*
G01X901232Y1504372D02*
X901902D01*
G01X899222D02*
X899892D01*
G01X901902Y1501748D02*
X901232D01*
G01X899892D02*
X899222D01*
G01X900060Y1510770D02*
X899054Y1510606D01*
G01X901232Y1506505D02*
X902238Y1506669D01*
G01X899892Y1511590D02*
X899054Y1511426D01*
G01X901400Y1505685D02*
X902238Y1505849D01*
G01X900227Y1516512D02*
X900562Y1516348D01*
G01X903410Y1510934D02*
X902740Y1511262D01*
G01D02*
X902238Y1511426D01*
G01D02*
X901400Y1511590D01*
G01X899054Y1505849D02*
X899892Y1505685D01*
G01X902238Y1510606D02*
X901232Y1510770D01*
G01X899054Y1506669D02*
X900060Y1506505D01*
G01X904583Y1499451D02*
X900897D01*
G01Y1494858D02*
X904583D01*
G01X903243Y1509950D02*
X902238Y1510606D01*
G01X900060Y1516676D02*
X900227Y1516512D01*
G01X899892Y1516183D02*
X899389Y1516676D01*
G01X903913Y1510442D02*
X903410Y1510934D01*
G01X900060Y1514051D02*
X900395Y1513723D01*
G01X899725D02*
X899389Y1514051D01*
G01X903578Y1509458D02*
X903243Y1509950D01*
G01X899892Y1517004D02*
X900060Y1516676D01*
G01X904415Y1509622D02*
X903913Y1510442D01*
G01X899389Y1516676D02*
X899222Y1517168D01*
G01X899892Y1514543D02*
X900060Y1514051D01*
G01X899389D02*
X899222Y1514543D01*
G01X904583Y1508638D02*
X904415Y1509622D01*
G01X903745Y1508638D02*
X903578Y1509458D01*
G01X904583Y1494858D02*
Y1493874D01*
G01Y1500435D02*
Y1499451D01*
G01Y1513723D02*
Y1512903D01*
G01Y1516348D02*
Y1515527D01*
G01Y1518972D02*
Y1518152D01*
G01X901902Y1504372D02*
Y1501748D01*
G01X901232D02*
Y1504372D01*
G01X900897Y1499451D02*
Y1494858D01*
G01X899892D02*
Y1499451D01*
G01Y1504372D02*
Y1501748D01*
G01Y1514871D02*
Y1514543D01*
G01Y1517496D02*
Y1517004D01*
G01X899222Y1517168D02*
Y1517824D01*
G01Y1514543D02*
Y1515199D01*
G01Y1512903D02*
Y1513723D01*
G01Y1501748D02*
Y1504372D01*
G01X903578Y1507817D02*
X903745Y1508638D01*
G01X904415Y1507653D02*
X904583Y1508638D01*
G01X899222Y1515199D02*
X899389Y1515691D01*
G01X899222Y1517824D02*
X899389Y1518316D01*
G01X903243Y1507325D02*
X903578Y1507817D01*
G01X903913Y1506833D02*
X904415Y1507653D01*
G01X900060Y1515199D02*
X899892Y1514871D01*
G01X900060Y1517824D02*
X899892Y1517496D01*
G01X903410Y1506341D02*
X903913Y1506833D01*
G01X902238Y1506669D02*
X903243Y1507325D01*
G01X900227Y1515363D02*
X900060Y1515199D01*
G01X899389Y1515691D02*
X899892Y1516183D01*
G01X900227Y1517988D02*
X900060Y1517824D01*
G01X899389Y1518316D02*
X899725Y1518644D01*
G01X902238Y1505849D02*
X902740Y1506013D01*
G01X899725Y1518644D02*
X900562Y1518972D01*
G01X902740Y1506013D02*
X903410Y1506341D01*
G01X900562Y1515527D02*
X900227Y1515363D01*
G01X900562Y1518152D02*
X900227Y1517988D01*
G01X931961Y1568371D02*
G03X922119Y1578213I-9842J0D01*
G01X900562Y1526354D02*
X904583D01*
G01Y1525534D02*
X900562D01*
G01Y1523729D02*
X904583D01*
G01Y1522909D02*
X900562D01*
G01X900395Y1521105D02*
X904583D01*
G01X899222D02*
X899725D01*
G01X904583Y1520285D02*
X899222D01*
G01X900227Y1523893D02*
X900562Y1523729D01*
G01X900060Y1524058D02*
X900227Y1523893D01*
G01X899892Y1523565D02*
X899389Y1524058D01*
G01X900060Y1521433D02*
X900395Y1521105D01*
G01X899725D02*
X899389Y1521433D01*
G01X899892Y1524386D02*
X900060Y1524058D01*
G01X899389D02*
X899222Y1524550D01*
G01X899892Y1521925D02*
X900060Y1521433D01*
G01X899389D02*
X899222Y1521925D01*
G01X904583Y1521105D02*
Y1520285D01*
G01Y1523729D02*
Y1522909D01*
G01Y1526354D02*
Y1525534D01*
G01X899892Y1522253D02*
Y1521925D01*
G01Y1524878D02*
Y1524386D01*
G01X899222Y1524550D02*
Y1525206D01*
G01Y1521925D02*
Y1522581D01*
G01Y1520285D02*
Y1521105D01*
G01Y1522581D02*
X899389Y1523073D01*
G01X899222Y1525206D02*
X899389Y1525698D01*
G01X900060Y1522581D02*
X899892Y1522253D01*
G01X900060Y1525206D02*
X899892Y1524878D01*
G01X900227Y1522745D02*
X900060Y1522581D01*
G01X899389Y1523073D02*
X899892Y1523565D01*
G01X900227Y1525370D02*
X900060Y1525206D01*
G01X899389Y1525698D02*
X899725Y1526026D01*
G01D02*
X900562Y1526354D01*
G01Y1522909D02*
X900227Y1522745D01*
G01X900562Y1525534D02*
X900227Y1525370D01*
G01X901646Y1672485D02*
X899678D01*
G01X901646Y1665635D02*
X899678D01*
G01X899284Y1665044D02*
X901253D01*
G01X901646D02*
X901253D01*
G01D02*
X899284D01*
G01X901253Y1663076D02*
X899284D01*
G01X901646D02*
X901253D01*
G01D02*
X899284D01*
G01X901646Y1662485D02*
X899678D01*
G01X901646Y1655635D02*
X899678D01*
G01X899284Y1655044D02*
X901253D01*
G01X901646D02*
X901253D01*
G01D02*
X899284D01*
G01X901253Y1654454D02*
X901353D01*
G01X901018D02*
X901253D01*
G01Y1654207D02*
X901311D01*
G01X899678D02*
X901253D01*
G01X901646Y1653961D02*
X901253D01*
G01D02*
X899678D01*
G01X901253Y1653076D02*
X899284D01*
G01X901646D02*
X901253D01*
G01D02*
X899284D01*
G01X901646Y1652485D02*
X899284D01*
G01X901353Y1654454D02*
X901646Y1654207D01*
G01X901311D02*
X901253Y1654257D01*
G01D02*
X901018Y1654454D01*
G01X899284Y1656107D02*
X899678Y1655635D01*
G01X899284Y1666343D02*
X899678Y1665635D01*
G01X905583Y1646934D02*
Y1681186D01*
G01X901646Y1665044D02*
Y1673076D01*
G01Y1655044D02*
Y1663076D01*
G01Y1650871D02*
Y1653076D01*
G01Y1654207D02*
Y1653961D01*
G01X901253Y1655044D02*
Y1653076D01*
G01Y1665044D02*
Y1663076D01*
G01X900505Y1655044D02*
Y1653076D01*
G01Y1665044D02*
Y1663076D01*
G01X899678Y1653961D02*
Y1654207D01*
G01X899284Y1672091D02*
Y1675635D01*
G01Y1661776D02*
Y1666343D01*
G01Y1663076D02*
Y1665044D01*
G01Y1652485D02*
Y1656107D01*
G01Y1655044D02*
Y1653076D01*
G01X899678Y1662485D02*
X899284Y1661776D01*
G01X899678Y1672485D02*
X899284Y1672091D01*
G01X901646Y1675635D02*
X899284D01*
G01Y1675044D02*
X901253D01*
G01X901646D02*
X901253D01*
G01D02*
X899284D01*
G01Y1673076D02*
X901253D01*
G01X901646D02*
X901253D01*
G01D02*
X899284D01*
G01X901646Y1675044D02*
Y1677249D01*
G01X901253Y1675044D02*
Y1673076D01*
G01X900505Y1675044D02*
Y1673076D01*
G01X899284Y1675044D02*
Y1673076D01*
G01X992394Y1734079D02*
X938457D01*
G01X992394D02*
X938457D01*
G01D02*
Y1901008D01*
G01Y1734079D02*
Y1901008D01*
G01X905583Y1774631D02*
Y1808883D01*
G01X984126Y1791953D02*
G03I-18701J0D01*
G01X981173D02*
G03I-15748J0D01*
G01X901646Y1803331D02*
X899284D01*
G01Y1802741D02*
X901253D01*
G01X901646D02*
X901253D01*
G01D02*
X899284D01*
G01Y1800772D02*
X901253D01*
G01X901646D02*
X901253D01*
G01D02*
X899284D01*
G01X901646Y1800182D02*
X899678D01*
G01X901646Y1793331D02*
X899678D01*
G01X899284Y1792741D02*
X901253D01*
G01X901646D02*
X901253D01*
G01D02*
X899284D01*
G01X901253Y1790772D02*
X899284D01*
G01X901646D02*
X901253D01*
G01D02*
X899284D01*
G01X901646Y1790182D02*
X899678D01*
G01X901646Y1783331D02*
X899678D01*
G01X899284Y1782741D02*
X901253D01*
G01X901646D02*
X901253D01*
G01D02*
X899284D01*
G01X901253Y1782150D02*
X901353D01*
G01X901018D02*
X901253D01*
G01Y1781904D02*
X901311D01*
G01X899678D02*
X901253D01*
G01X901646Y1781658D02*
X901253D01*
G01D02*
X899678D01*
G01X901253Y1780772D02*
X899284D01*
G01X901646D02*
X901253D01*
G01D02*
X899284D01*
G01X901646Y1780182D02*
X899284D01*
G01X901353Y1782150D02*
X901646Y1781904D01*
G01X901311D02*
X901253Y1781954D01*
G01D02*
X901018Y1782150D01*
G01X899284Y1783804D02*
X899678Y1783331D01*
G01X899284Y1794040D02*
X899678Y1793331D01*
G01X901646Y1802741D02*
Y1804946D01*
G01Y1792741D02*
Y1800772D01*
G01Y1782741D02*
Y1790772D01*
G01Y1778568D02*
Y1780772D01*
G01Y1781904D02*
Y1781658D01*
G01X901253Y1782741D02*
Y1780772D01*
G01Y1792741D02*
Y1790772D01*
G01Y1802741D02*
Y1800772D01*
G01X900505Y1782741D02*
Y1780772D01*
G01Y1792741D02*
Y1790772D01*
G01Y1802741D02*
Y1800772D01*
G01X899678Y1781658D02*
Y1781904D01*
G01X899284Y1799788D02*
Y1803331D01*
G01Y1789473D02*
Y1794040D01*
G01Y1790772D02*
Y1792741D01*
G01Y1780182D02*
Y1783804D01*
G01Y1782741D02*
Y1780772D01*
G01Y1802741D02*
Y1800772D01*
G01X899678Y1790182D02*
X899284Y1789473D01*
G01X899678Y1800182D02*
X899284Y1799788D01*
G01X981173Y1867150D02*
G03I-15748J0D01*
G01X984126D02*
G03I-18701J0D01*
G01X938457Y1901008D02*
X992394D01*
G01X938457D02*
X992394D01*
G01X922119Y1877583D02*
G03X931961Y1887426I-1J9843D01*
G01D02*
Y2001599D01*
G01X901696Y1927861D02*
Y1926877D01*
G01X937867Y1977190D02*
G03X941804Y1973253I3937J0D01*
G01X937867Y1977190D02*
G03X941804Y1973253I3937J0D01*
G01X921922Y1944513D02*
G03I-5709J0D01*
G01X941804Y1973253D02*
X1071725D01*
G01X941804D02*
X1071725D01*
G01X899853Y1944266D02*
X899350Y1944430D01*
G01X900523Y1943937D02*
X899853Y1944266D01*
G01X900356Y1942953D02*
X899350Y1943609D01*
G01X901026Y1943445D02*
X900523Y1943937D01*
G01X901528Y1942625D02*
X901026Y1943445D01*
G01X900691Y1942461D02*
X900356Y1942953D01*
G01X901696Y1941641D02*
X901528Y1942625D01*
G01X900858Y1941641D02*
X900691Y1942461D01*
G01X937867Y2008686D02*
Y1977190D01*
G01Y2008686D02*
Y1977190D01*
G01X901696Y1933439D02*
Y1932454D01*
G01Y1949351D02*
Y1948531D01*
G01Y1946726D02*
Y1945906D01*
G01Y1951975D02*
Y1951155D01*
G01Y1954108D02*
Y1953288D01*
G01Y1956733D02*
Y1955912D01*
G01Y1959357D02*
Y1958537D01*
G01X899015Y1937376D02*
Y1934751D01*
G01X900691Y1940821D02*
X900858Y1941641D01*
G01X901528Y1940657D02*
X901696Y1941641D01*
G01X900356Y1940328D02*
X900691Y1940821D01*
G01X901026Y1939836D02*
X901528Y1940657D01*
G01X900523Y1939344D02*
X901026Y1939836D01*
G01X899853Y1939016D02*
X900523Y1939344D01*
G01X899350Y1939672D02*
X900356Y1940328D01*
G01X899350Y1938852D02*
X899853Y1939016D01*
G01X937867Y2008686D02*
G03X933930Y2012623I-3937J0D01*
G01X937867Y2008686D02*
G03X933930Y2012623I-3937J0D01*
G01X931961Y2001599D02*
G03X922119Y2011442I-9842J1D01*
G01X994678Y385024D02*
Y152032D01*
G01X993378Y182028D02*
Y355028D01*
G01X963378Y153528D02*
Y189528D01*
G01D02*
Y190028D01*
G01X955478Y194528D02*
Y187528D01*
G01X951028Y188478D02*
Y178578D01*
G01X963378Y189528D02*
X993378D01*
G01Y182028D02*
X963378D01*
G01X981408Y227028D02*
G03X977948I-1730J-1019D01*
G01X977926Y235028D02*
G03X981430I1752J981D01*
G01X977948Y227028D02*
G03X981408I1730J-1019D01*
G01X981430Y235028D02*
G03X977926I-1752J981D01*
G01X981408Y207028D02*
G03X977948I-1730J-1019D01*
G01X977926Y215028D02*
G03X981430I1752J981D01*
G01X977948Y207028D02*
G03X981408I1730J-1019D01*
G01X981430Y215028D02*
G03X977926I-1752J981D01*
G01X971408Y227028D02*
G03X967948I-1730J-1019D01*
G01X967926Y235028D02*
G03X971430I1752J981D01*
G01X967948Y227028D02*
G03X971408I1730J-1019D01*
G01X971430Y235028D02*
G03X967926I-1752J981D01*
G01X971408Y207028D02*
G03X967948I-1730J-1019D01*
G01X967926Y215028D02*
G03X971430I1752J981D01*
G01X967948Y207028D02*
G03X971408I1730J-1019D01*
G01X971430Y215028D02*
G03X967926I-1752J981D01*
G01X961408Y207028D02*
G03X957948I-1730J-1019D01*
G01X961408Y227028D02*
G03X957948I-1730J-1019D01*
G01X957926Y215028D02*
G03X961430I1752J981D01*
G01X957926Y235028D02*
G03X961430I1752J981D01*
G01X957948Y207028D02*
G03X961408I1730J-1019D01*
G01X957948Y227028D02*
G03X961408I1730J-1019D01*
G01X961430Y215028D02*
G03X957926I-1752J981D01*
G01X961430Y235028D02*
G03X957926I-1752J981D01*
G01X990378Y342528D02*
Y194528D01*
G01X988378Y198528D02*
Y243528D01*
G01X982308Y215028D02*
Y207028D01*
G01Y235028D02*
Y227028D01*
G01X980928Y235028D02*
Y237028D01*
G01Y225028D02*
Y227028D01*
G01Y215028D02*
Y217028D01*
G01Y205028D02*
Y207028D01*
G01X978428D02*
Y205028D01*
G01Y217028D02*
Y215028D01*
G01Y227028D02*
Y225028D01*
G01Y237028D02*
Y235028D01*
G01X978384Y207028D02*
Y205028D01*
G01Y217028D02*
Y215028D01*
G01Y227028D02*
Y225028D01*
G01Y237028D02*
Y235028D01*
G01X973591Y207028D02*
Y205028D01*
G01Y217028D02*
Y215028D01*
G01Y227028D02*
Y225028D01*
G01Y237028D02*
Y235028D01*
G01X970928D02*
Y237028D01*
G01Y225028D02*
Y227028D01*
G01Y215028D02*
Y217028D01*
G01Y205028D02*
Y207028D01*
G01X968428D02*
Y205028D01*
G01Y217028D02*
Y215028D01*
G01Y227028D02*
Y225028D01*
G01Y237028D02*
Y235028D01*
G01X960928D02*
Y237028D01*
G01Y225028D02*
Y227028D01*
G01Y215028D02*
Y217028D01*
G01Y205028D02*
Y207028D01*
G01X958428D02*
Y205028D01*
G01Y217028D02*
Y215028D01*
G01Y227028D02*
Y225028D01*
G01Y237028D02*
Y235028D01*
G01X952315Y207028D02*
Y205028D01*
G01Y217028D02*
Y215028D01*
G01Y227028D02*
Y225028D01*
G01Y237028D02*
Y235028D01*
G01X950928D02*
Y237028D01*
G01Y225028D02*
Y227028D01*
G01Y215028D02*
Y217028D01*
G01Y205028D02*
Y207028D01*
G01X980928Y237028D02*
X978428D01*
G01Y225028D02*
X980928D01*
G01Y217028D02*
X978428D01*
G01Y205028D02*
X980928D01*
G01X990378Y194528D02*
X955478D01*
G01X963378Y190028D02*
X993378D01*
G01X981686Y248528D02*
G03I-2008J0D01*
G01Y258528D02*
G03I-2008J0D01*
G01Y268528D02*
G03I-2008J0D01*
G01Y278528D02*
G03I-2008J0D01*
G01Y288528D02*
G03I-2008J0D01*
G01X971686Y248528D02*
G03I-2008J0D01*
G01Y258528D02*
G03I-2008J0D01*
G01Y268528D02*
G03I-2008J0D01*
G01Y278528D02*
G03I-2008J0D01*
G01Y288528D02*
G03I-2008J0D01*
G01X961686Y268528D02*
G03I-2008J0D01*
G01Y278528D02*
G03I-2008J0D01*
G01Y288528D02*
G03I-2008J0D01*
G01Y248528D02*
G03I-2008J0D01*
G01Y258528D02*
G03I-2008J0D01*
G01X980928Y249778D02*
X981318Y250169D01*
G01X978428Y247278D02*
X978037Y246888D01*
G01X980928Y259778D02*
X981318Y260169D01*
G01X968037Y246888D02*
X968428Y247278D01*
G01X971318Y250169D02*
X970928Y249778D01*
G01X978428Y257278D02*
X978037Y256888D01*
G01X980928Y269778D02*
X981318Y270169D01*
G01X968037Y256888D02*
X968428Y257278D01*
G01X958037Y246888D02*
X958428Y247278D01*
G01X961318Y250169D02*
X960928Y249778D01*
G01X971318Y260169D02*
X970928Y259778D01*
G01X978428Y267278D02*
X978037Y266888D01*
G01X980928Y279778D02*
X981318Y280169D01*
G01X968037Y266888D02*
X968428Y267278D01*
G01X958037Y256888D02*
X958428Y257278D01*
G01X951318Y250169D02*
X950928Y249778D01*
G01X961318Y260169D02*
X960928Y259778D01*
G01X971318Y270169D02*
X970928Y269778D01*
G01X978428Y277278D02*
X978037Y276888D01*
G01X980928Y289778D02*
X981318Y290169D01*
G01X968037Y276888D02*
X968428Y277278D01*
G01X958037Y266888D02*
X958428Y267278D01*
G01X951318Y260169D02*
X950928Y259778D01*
G01X961318Y270169D02*
X960928Y269778D01*
G01X971318Y280169D02*
X970928Y279778D01*
G01X978428Y287278D02*
X978037Y286888D01*
G01X968037D02*
X968428Y287278D01*
G01X958037Y276888D02*
X958428Y277278D01*
G01X951318Y270169D02*
X950928Y269778D01*
G01X961318Y280169D02*
X960928Y279778D01*
G01X971318Y290169D02*
X970928Y289778D01*
G01X958037Y286888D02*
X958428Y287278D01*
G01X951318Y280169D02*
X950928Y279778D01*
G01X961318Y290169D02*
X960928Y289778D01*
G01X951318Y290169D02*
X950928Y289778D01*
G01X988178Y243528D02*
Y293528D01*
G01X981318Y286888D02*
Y290169D01*
G01Y276888D02*
Y280169D01*
G01Y266888D02*
Y270169D01*
G01Y256888D02*
Y260169D01*
G01Y246888D02*
Y250169D01*
G01X981058Y249908D02*
Y247148D01*
G01Y259908D02*
Y257148D01*
G01Y269908D02*
Y267148D01*
G01Y279908D02*
Y277148D01*
G01Y289908D02*
Y287148D01*
G01X980928Y249778D02*
Y247278D01*
G01Y259778D02*
Y257278D01*
G01Y269778D02*
Y267278D01*
G01Y279778D02*
Y277278D01*
G01Y289778D02*
Y287278D01*
G01X978428Y249778D02*
Y247278D01*
G01Y259778D02*
Y257278D01*
G01Y269778D02*
Y267278D01*
G01Y279778D02*
Y277278D01*
G01Y289778D02*
Y287278D01*
G01X978298Y249908D02*
Y247148D01*
G01Y259908D02*
Y257148D01*
G01Y269908D02*
Y267148D01*
G01Y279908D02*
Y277148D01*
G01Y289908D02*
Y287148D01*
G01X978037Y250169D02*
Y246888D01*
G01Y260169D02*
Y256888D01*
G01Y270169D02*
Y266888D01*
G01Y280169D02*
Y276888D01*
G01Y290169D02*
Y286888D01*
G01X971318Y250169D02*
Y246888D01*
G01Y260169D02*
Y256888D01*
G01Y270169D02*
Y266888D01*
G01Y280169D02*
Y276888D01*
G01Y290169D02*
Y286888D01*
G01X971058Y249908D02*
Y247148D01*
G01Y259908D02*
Y257148D01*
G01Y269908D02*
Y267148D01*
G01Y279908D02*
Y277148D01*
G01Y289908D02*
Y287148D01*
G01X970928Y249778D02*
Y247278D01*
G01Y259778D02*
Y257278D01*
G01Y269778D02*
Y267278D01*
G01Y279778D02*
Y277278D01*
G01Y289778D02*
Y287278D01*
G01X968428D02*
Y289778D01*
G01Y277278D02*
Y279778D01*
G01Y267278D02*
Y269778D01*
G01Y257278D02*
Y259778D01*
G01Y247278D02*
Y249778D01*
G01X968298Y287148D02*
Y289908D01*
G01Y277148D02*
Y279908D01*
G01Y267148D02*
Y269908D01*
G01Y257148D02*
Y259908D01*
G01Y247148D02*
Y249908D01*
G01X968037Y286888D02*
Y290169D01*
G01Y276888D02*
Y280169D01*
G01Y266888D02*
Y270169D01*
G01Y256888D02*
Y260169D01*
G01Y246888D02*
Y250169D01*
G01X961318D02*
Y246888D01*
G01Y260169D02*
Y256888D01*
G01Y270169D02*
Y266888D01*
G01Y280169D02*
Y276888D01*
G01Y290169D02*
Y286888D01*
G01X961058Y249908D02*
Y247148D01*
G01Y259908D02*
Y257148D01*
G01Y269908D02*
Y267148D01*
G01Y279908D02*
Y277148D01*
G01Y289908D02*
Y287148D01*
G01X960928Y249778D02*
Y247278D01*
G01Y259778D02*
Y257278D01*
G01Y269778D02*
Y267278D01*
G01Y279778D02*
Y277278D01*
G01Y289778D02*
Y287278D01*
G01X958428D02*
Y289778D01*
G01Y277278D02*
Y279778D01*
G01Y267278D02*
Y269778D01*
G01Y257278D02*
Y259778D01*
G01Y247278D02*
Y249778D01*
G01X958298Y287148D02*
Y289908D01*
G01Y277148D02*
Y279908D01*
G01Y267148D02*
Y269908D01*
G01Y257148D02*
Y259908D01*
G01Y247148D02*
Y249908D01*
G01X958037Y286888D02*
Y290169D01*
G01Y276888D02*
Y280169D01*
G01Y266888D02*
Y270169D01*
G01Y256888D02*
Y260169D01*
G01Y246888D02*
Y250169D01*
G01X951318D02*
Y246888D01*
G01Y260169D02*
Y256888D01*
G01Y270169D02*
Y266888D01*
G01Y280169D02*
Y276888D01*
G01Y290169D02*
Y286888D01*
G01X951058Y249908D02*
Y247148D01*
G01Y259908D02*
Y257148D01*
G01Y269908D02*
Y267148D01*
G01Y279908D02*
Y277148D01*
G01Y289908D02*
Y287148D01*
G01X950928Y249778D02*
Y247278D01*
G01Y259778D02*
Y257278D01*
G01Y269778D02*
Y267278D01*
G01Y279778D02*
Y277278D01*
G01Y289778D02*
Y287278D01*
G01X980928D02*
X981318Y286888D01*
G01X978037Y290169D02*
X978428Y289778D01*
G01X980928Y277278D02*
X981318Y276888D01*
G01X978037Y280169D02*
X978428Y279778D01*
G01X970928Y287278D02*
X971318Y286888D01*
G01X968037Y290169D02*
X968428Y289778D01*
G01X980928Y267278D02*
X981318Y266888D01*
G01X978037Y270169D02*
X978428Y269778D01*
G01X970928Y277278D02*
X971318Y276888D01*
G01X968037Y280169D02*
X968428Y279778D01*
G01X960928Y287278D02*
X961318Y286888D01*
G01X958037Y290169D02*
X958428Y289778D01*
G01X980928Y257278D02*
X981318Y256888D01*
G01X978037Y260169D02*
X978428Y259778D01*
G01X970928Y267278D02*
X971318Y266888D01*
G01X968037Y270169D02*
X968428Y269778D01*
G01X960928Y277278D02*
X961318Y276888D01*
G01X958037Y280169D02*
X958428Y279778D01*
G01X950928Y287278D02*
X951318Y286888D01*
G01X980928Y247278D02*
X981318Y246888D01*
G01X978037Y250169D02*
X978428Y249778D01*
G01X970928Y257278D02*
X971318Y256888D01*
G01X968037Y260169D02*
X968428Y259778D01*
G01X960928Y267278D02*
X961318Y266888D01*
G01X958037Y270169D02*
X958428Y269778D01*
G01X950928Y277278D02*
X951318Y276888D01*
G01X970928Y247278D02*
X971318Y246888D01*
G01X968037Y250169D02*
X968428Y249778D01*
G01X960928Y257278D02*
X961318Y256888D01*
G01X958037Y260169D02*
X958428Y259778D01*
G01X950928Y267278D02*
X951318Y266888D01*
G01X960928Y247278D02*
X961318Y246888D01*
G01X958037Y250169D02*
X958428Y249778D01*
G01X950928Y257278D02*
X951318Y256888D01*
G01X950928Y247278D02*
X951318Y246888D01*
G01X968037Y290169D02*
X971318D01*
G01X958037D02*
X961318D01*
G01X981318D02*
X978037D01*
G01X978298Y289908D02*
X981058D01*
G01X968298D02*
X971058D01*
G01X958298D02*
X961058D01*
G01X978428Y289778D02*
X980928D01*
G01X968428D02*
X970928D01*
G01X958428D02*
X960928D01*
G01Y287278D02*
X958428D01*
G01X970928D02*
X968428D01*
G01X980928D02*
X978428D01*
G01X961058Y287148D02*
X958298D01*
G01X971058D02*
X968298D01*
G01X981058D02*
X978298D01*
G01X978037Y286888D02*
X981318D01*
G01X961318D02*
X958037D01*
G01X971318D02*
X968037D01*
G01Y280169D02*
X971318D01*
G01X958037D02*
X961318D01*
G01X981318D02*
X978037D01*
G01X978298Y279908D02*
X981058D01*
G01X968298D02*
X971058D01*
G01X958298D02*
X961058D01*
G01X978428Y279778D02*
X980928D01*
G01X968428D02*
X970928D01*
G01X958428D02*
X960928D01*
G01Y277278D02*
X958428D01*
G01X970928D02*
X968428D01*
G01X980928D02*
X978428D01*
G01X961058Y277148D02*
X958298D01*
G01X971058D02*
X968298D01*
G01X981058D02*
X978298D01*
G01X978037Y276888D02*
X981318D01*
G01X961318D02*
X958037D01*
G01X971318D02*
X968037D01*
G01Y270169D02*
X971318D01*
G01X958037D02*
X961318D01*
G01X981318D02*
X978037D01*
G01X978298Y269908D02*
X981058D01*
G01X968298D02*
X971058D01*
G01X958298D02*
X961058D01*
G01X978428Y269778D02*
X980928D01*
G01X968428D02*
X970928D01*
G01X958428D02*
X960928D01*
G01Y267278D02*
X958428D01*
G01X970928D02*
X968428D01*
G01X980928D02*
X978428D01*
G01X961058Y267148D02*
X958298D01*
G01X971058D02*
X968298D01*
G01X981058D02*
X978298D01*
G01X978037Y266888D02*
X981318D01*
G01X961318D02*
X958037D01*
G01X971318D02*
X968037D01*
G01Y260169D02*
X971318D01*
G01X958037D02*
X961318D01*
G01X981318D02*
X978037D01*
G01X978298Y259908D02*
X981058D01*
G01X968298D02*
X971058D01*
G01X958298D02*
X961058D01*
G01X978428Y259778D02*
X980928D01*
G01X968428D02*
X970928D01*
G01X958428D02*
X960928D01*
G01Y257278D02*
X958428D01*
G01X970928D02*
X968428D01*
G01X980928D02*
X978428D01*
G01X961058Y257148D02*
X958298D01*
G01X971058D02*
X968298D01*
G01X981058D02*
X978298D01*
G01X978037Y256888D02*
X981318D01*
G01X961318D02*
X958037D01*
G01X971318D02*
X968037D01*
G01Y250169D02*
X971318D01*
G01X958037D02*
X961318D01*
G01X981318D02*
X978037D01*
G01X978298Y249908D02*
X981058D01*
G01X968298D02*
X971058D01*
G01X958298D02*
X961058D01*
G01X978428Y249778D02*
X980928D01*
G01X968428D02*
X970928D01*
G01X958428D02*
X960928D01*
G01Y247278D02*
X958428D01*
G01X970928D02*
X968428D01*
G01X980928D02*
X978428D01*
G01X961058Y247148D02*
X958298D01*
G01X971058D02*
X968298D01*
G01X981058D02*
X978298D01*
G01X978037Y246888D02*
X981318D01*
G01X961318D02*
X958037D01*
G01X971318D02*
X968037D01*
G01X988178Y243528D02*
X990373D01*
G01X981430Y302029D02*
G03X977926I-1752J-981D01*
G01X981430Y322029D02*
G03X977926I-1752J-981D01*
G01X977948Y310028D02*
G03X981408I1730J1020D01*
G01X977948Y330028D02*
G03X981408I1730J1020D01*
G01X977926Y302029D02*
G03X981430I1752J-981D01*
G01X977926Y322029D02*
G03X981430I1752J-981D01*
G01X981408Y310028D02*
G03X977948I-1730J1020D01*
G01X981408Y330028D02*
G03X977948I-1730J1020D01*
G01X971430Y302029D02*
G03X967926I-1752J-981D01*
G01X971430Y322029D02*
G03X967926I-1752J-981D01*
G01X967948Y310028D02*
G03X971408I1730J1020D01*
G01X967948Y330028D02*
G03X971408I1730J1020D01*
G01X967926Y302029D02*
G03X971430I1752J-981D01*
G01X967926Y322029D02*
G03X971430I1752J-981D01*
G01X971408Y310028D02*
G03X967948I-1730J1020D01*
G01X971408Y330028D02*
G03X967948I-1730J1020D01*
G01X961430Y322029D02*
G03X957926I-1752J-981D01*
G01X957948Y330028D02*
G03X961408I1730J1020D01*
G01X957926Y322029D02*
G03X961430I1752J-981D01*
G01X961408Y330028D02*
G03X957948I-1730J1020D01*
G01X961430Y302029D02*
G03X957926I-1752J-981D01*
G01X957948Y310028D02*
G03X961408I1730J1020D01*
G01X957926Y302029D02*
G03X961430I1752J-981D01*
G01X961408Y310028D02*
G03X957948I-1730J1020D01*
G01X952816Y330875D02*
X952740Y330850D01*
G01Y330998D02*
X952816Y331022D01*
G01X952916Y330949D02*
X952816Y330875D01*
G01Y331022D02*
X952866Y331072D01*
G01X952991Y331047D02*
X952916Y330949D01*
G01X952866Y331072D02*
X952891Y331145D01*
G01X953017Y331170D02*
X952991Y331047D01*
G01X988378Y293528D02*
Y338528D01*
G01X982308Y310028D02*
Y302028D01*
G01Y330028D02*
Y322028D01*
G01X980928Y330028D02*
Y332028D01*
G01Y320028D02*
Y322028D01*
G01Y310028D02*
Y312028D01*
G01Y300028D02*
Y302028D01*
G01X978428D02*
Y300028D01*
G01Y312028D02*
Y310028D01*
G01Y322028D02*
Y320028D01*
G01Y332028D02*
Y330028D01*
G01X978384Y302028D02*
Y300028D01*
G01Y312028D02*
Y310028D01*
G01Y322028D02*
Y320028D01*
G01Y332028D02*
Y330028D01*
G01X973591Y302028D02*
Y300028D01*
G01Y312028D02*
Y310028D01*
G01Y322028D02*
Y320028D01*
G01Y332028D02*
Y330028D01*
G01X970928D02*
Y332028D01*
G01Y320028D02*
Y322028D01*
G01Y310028D02*
Y312028D01*
G01Y300028D02*
Y302028D01*
G01X968428D02*
Y300028D01*
G01Y312028D02*
Y310028D01*
G01Y322028D02*
Y320028D01*
G01Y332028D02*
Y330028D01*
G01X960928D02*
Y332028D01*
G01Y320028D02*
Y322028D01*
G01Y310028D02*
Y312028D01*
G01Y300028D02*
Y302028D01*
G01X958428D02*
Y300028D01*
G01Y312028D02*
Y310028D01*
G01Y322028D02*
Y320028D01*
G01Y332028D02*
Y330028D01*
G01X955478Y349528D02*
Y342528D01*
G01X953017Y330506D02*
Y330358D01*
G01Y331761D02*
Y331170D01*
G01X952891Y331145D02*
Y331613D01*
G01X952514D02*
Y331145D01*
G01X952363Y331170D02*
Y331613D01*
G01X952315Y302028D02*
Y300028D01*
G01Y312028D02*
Y310028D01*
G01Y322028D02*
Y320028D01*
G01Y332028D02*
Y330028D01*
G01X951835Y331613D02*
Y331761D01*
G01Y330358D02*
Y330506D01*
G01X950928Y330028D02*
Y332028D01*
G01Y320028D02*
Y322028D01*
G01Y310028D02*
Y312028D01*
G01Y300028D02*
Y302028D01*
G01X952388Y331047D02*
X952363Y331170D01*
G01X952514Y331145D02*
X952539Y331072D01*
G01X952464Y330949D02*
X952388Y331047D01*
G01X952539Y331072D02*
X952589Y331022D01*
G01X952841Y330653D02*
X953017Y330506D01*
G01X952816D02*
X952640Y330653D01*
G01X952564Y330875D02*
X952464Y330949D01*
G01X952589Y331022D02*
X952665Y330998D01*
G01X952640Y330850D02*
X952564Y330875D01*
G01X955478Y342528D02*
X990378D01*
G01X980928Y332028D02*
X978428D01*
G01X951835Y331761D02*
X953017D01*
G01X952891Y331613D02*
X952514D01*
G01X952363D02*
X951835D01*
G01X952665Y330998D02*
X952740D01*
G01Y330850D02*
X952640D01*
G01Y330653D02*
X952841D01*
G01X951835Y330506D02*
X952816D01*
G01X953017Y330358D02*
X951835D01*
G01X978428Y320028D02*
X980928D01*
G01Y312028D02*
X978428D01*
G01Y300028D02*
X980928D01*
G01X988178Y293528D02*
X990373D01*
G01X963378Y347528D02*
Y383528D01*
G01Y347028D02*
Y347528D01*
G01X951028Y358478D02*
Y348578D01*
G01X963378Y355028D02*
X993378D01*
G01Y347528D02*
X963378D01*
G01X993378Y347028D02*
X963378D01*
G01X983143Y611442D02*
Y611343D01*
G01X982355D02*
Y611442D01*
G01X982158Y612190D02*
Y610300D01*
G01Y619670D02*
Y617780D01*
G01X981568Y612190D02*
Y610300D01*
G01Y619670D02*
Y617780D01*
G01X981374Y612190D02*
Y610300D01*
G01Y619670D02*
Y617780D01*
G01X981240Y612190D02*
Y610300D01*
G01Y619670D02*
Y617780D01*
G01X980792Y612190D02*
Y610300D01*
G01Y619670D02*
Y617780D01*
G01X980658Y612190D02*
Y610300D01*
G01Y619670D02*
Y617780D01*
G01X980464Y612190D02*
Y610300D01*
G01Y619670D02*
Y617780D01*
G01X979993Y609080D02*
Y620891D01*
G01X974481D02*
Y609080D01*
G01X974010Y615930D02*
Y614040D01*
G01X973816Y615930D02*
Y614040D01*
G01X973682Y615930D02*
Y614040D01*
G01X973234Y615930D02*
Y614040D01*
G01X973100Y615930D02*
Y614040D01*
G01X972906Y615930D02*
Y614040D01*
G01X972316Y615930D02*
Y614040D01*
G01X982489Y611343D02*
X982606Y611245D01*
G01X982472D02*
X982355Y611343D01*
G01X979993Y620891D02*
X974481D01*
G01X982158Y619670D02*
X979993D01*
G01X982158Y617780D02*
X979993D01*
G01X974481Y615930D02*
X972316D01*
G01X974481Y614040D02*
X972316D01*
G01X982158Y612190D02*
X979993D01*
G01X982355Y611442D02*
X983143D01*
G01Y611343D02*
X982489D01*
G01X982606Y611245D02*
X982472D01*
G01X982158Y610300D02*
X979993D01*
G01X974481Y609080D02*
X979993D01*
G01X998179Y977518D02*
Y954552D01*
G01X993153D02*
Y977518D01*
G01X977237Y949631D02*
Y954552D01*
G01X998179D02*
X1016607D01*
G01X977237D02*
X993153D01*
G01X1016607Y949631D02*
X977237D01*
G01X990640Y1006225D02*
X996503Y994742D01*
G01Y989001D02*
X988127Y1004585D01*
G01D02*
X990640Y1006225D01*
G01X1004880Y1004585D02*
X996503Y989001D01*
G01Y994742D02*
X1002367Y1006225D01*
G01X977237Y977518D02*
Y982439D01*
G01D02*
X1016607D01*
G01X993153Y977518D02*
X977237D01*
G01X1016607D02*
X998179D01*
G01X991477Y1042314D02*
X992315Y1038213D01*
G01X977237Y1042314D02*
X978075Y1038213D01*
G01X995666Y1041494D02*
X996503Y1039034D01*
G01X982263D02*
X981425Y1041494D01*
G01X978075Y1038213D02*
X980588Y1034112D01*
G01X996503Y1039034D02*
X998179Y1036573D01*
G01X992315Y1038213D02*
X995666Y1033292D01*
G01X983938Y1036573D02*
X982263Y1039034D01*
G01X998179Y1036573D02*
X999854Y1034933D01*
G01X980588Y1034112D02*
X983938Y1031652D01*
G01X986451Y1034933D02*
X983938Y1036573D01*
G01Y1031652D02*
X988127Y1030011D01*
G01X999854Y1034933D02*
X1002367Y1034112D01*
G01X988964D02*
X986451Y1034933D01*
G01X993990Y1033292D02*
X988964Y1034112D01*
G01X999854Y1053797D02*
X998179Y1052157D01*
G01D02*
X996503Y1049696D01*
G01X994828Y1054618D02*
X992315Y1050517D01*
G01X996503Y1049696D02*
X995666Y1047236D01*
G01X981425Y1046415D02*
X982263Y1048876D01*
G01X992315Y1050517D02*
X991477Y1046415D01*
G01X978075Y1049696D02*
X977237Y1045595D01*
G01X995666Y1047236D02*
Y1041494D01*
G01X991477Y1046415D02*
Y1042314D01*
G01X986451Y1052977D02*
Y1057078D01*
G01X981425Y1041494D02*
Y1046415D01*
G01X977237Y1017708D02*
Y1022629D01*
G01Y1045595D02*
Y1042314D01*
G01X983938Y1017708D02*
X989802Y1012787D01*
G01X983101D02*
X977237Y1017708D01*
G01X988127Y1030011D02*
X993990Y1029191D01*
G01X995666Y1033292D02*
X993990D01*
G01Y1029191D02*
X999854D01*
G01X977237Y1022629D02*
X1016607D01*
G01Y1017708D02*
X983938D01*
G01X989802Y1012787D02*
X983101D01*
G01X999854Y1029191D02*
X1005718Y1030011D01*
G01X1002367Y1054618D02*
X999854Y1053797D01*
G01X986451Y1057078D02*
X983938Y1056258D01*
G01X1001529Y1058719D02*
X997341Y1057078D01*
G01X983938Y1051337D02*
X986451Y1052977D01*
G01X983938Y1056258D02*
X980588Y1053797D01*
G01X997341Y1057078D02*
X994828Y1054618D01*
G01X982263Y1048876D02*
X983938Y1051337D01*
G01X980588Y1053797D02*
X978075Y1049696D01*
G01X993990Y1107931D02*
X995666Y1106291D01*
G01X992315D02*
X990640Y1107931D01*
G01X995666Y1106291D02*
X1016607D01*
G01X989802D02*
X992315D01*
G01X993153Y1110392D02*
X993990Y1107931D01*
G01X990640D02*
X989802Y1110392D01*
G01X990640Y1084145D02*
X989802Y1086606D01*
G01X993153Y1073482D02*
X993990Y1071022D01*
G01X990640D02*
X989802Y1073482D01*
G01X993153Y1085786D02*
X993990Y1084145D01*
G01D02*
X994828Y1083325D01*
G01X993153Y1081684D02*
X990640Y1084145D01*
G01X993990Y1071022D02*
X995666Y1069381D01*
G01X992315D02*
X990640Y1071022D01*
G01X994828Y1083325D02*
X996503Y1082505D01*
G01X1016607Y1102190D02*
X989802D01*
G01X996503Y1095628D02*
X1016607D01*
G01Y1091527D02*
X996503D01*
G01Y1082505D02*
X1016607D01*
G01Y1078404D02*
X996503D01*
G01X995666Y1069381D02*
X1016607D01*
G01X989802D02*
X992315D01*
G01X1016607Y1065280D02*
X989802D01*
G01Y1076763D02*
X990640Y1079224D01*
G01X993153Y1075123D02*
Y1073482D01*
G01Y1088246D02*
Y1085786D01*
G01X989802Y1102190D02*
Y1106291D01*
G01Y1086606D02*
Y1089887D01*
G01Y1073482D02*
Y1076763D01*
G01Y1065280D02*
Y1069381D01*
G01X992315Y1093988D02*
X996503Y1095628D01*
G01Y1078404D02*
X994828Y1077583D01*
G01X996503Y1091527D02*
X994828Y1090707D01*
G01Y1077583D02*
X993990Y1076763D01*
G01X990640Y1079224D02*
X993153Y1081684D01*
G01X994828Y1090707D02*
X993990Y1089887D01*
G01X990640Y1092347D02*
X992315Y1093988D01*
G01X993990Y1076763D02*
X993153Y1075123D01*
G01X993990Y1089887D02*
X993153Y1088246D01*
G01X989802Y1089887D02*
X990640Y1092347D01*
G01X993990Y1121055D02*
X994828Y1120234D01*
G01X993153Y1118594D02*
X990640Y1121055D01*
G01X994828Y1120234D02*
X996503Y1119414D01*
G01Y1132538D02*
X1016607D01*
G01Y1128436D02*
X996503D01*
G01Y1119414D02*
X1016607D01*
G01Y1115313D02*
X996503D01*
G01X990640Y1121055D02*
X989802Y1123515D01*
G01X993153Y1122695D02*
X993990Y1121055D01*
G01X993153Y1112032D02*
Y1110392D01*
G01Y1125156D02*
Y1122695D01*
G01X989802Y1123515D02*
Y1126796D01*
G01Y1110392D02*
Y1113673D01*
G01X994828Y1114493D02*
X993990Y1113673D01*
G01X990640Y1116133D02*
X993153Y1118594D01*
G01X994828Y1127616D02*
X993990Y1126796D01*
G01X990640Y1129257D02*
X992315Y1130897D01*
G01X993990Y1113673D02*
X993153Y1112032D01*
G01X993990Y1126796D02*
X993153Y1125156D01*
G01X989802Y1113673D02*
X990640Y1116133D01*
G01X989802Y1126796D02*
X990640Y1129257D01*
G01X992315Y1130897D02*
X996503Y1132538D01*
G01Y1115313D02*
X994828Y1114493D01*
G01X996503Y1128436D02*
X994828Y1127616D01*
G01X979993Y1309867D02*
X974481D01*
G01X982158Y1308646D02*
X979993D01*
G01X982158Y1306757D02*
X979993D01*
G01X974481Y1304906D02*
X972316D01*
G01X974481Y1303017D02*
X972316D01*
G01X982489Y1300320D02*
X982606Y1300221D01*
G01X982472D02*
X982355Y1300320D01*
G01X982158Y1301166D02*
X979993D01*
G01X982355Y1300418D02*
X983143D01*
G01Y1300320D02*
X982489D01*
G01X982606Y1300221D02*
X982472D01*
G01X982158Y1299276D02*
X979993D01*
G01X974481Y1298056D02*
X979993D01*
G01X983143Y1300418D02*
Y1300320D01*
G01X982355D02*
Y1300418D01*
G01X982158Y1301166D02*
Y1299276D01*
G01Y1308646D02*
Y1306757D01*
G01X981568Y1301166D02*
Y1299276D01*
G01Y1308646D02*
Y1306757D01*
G01X981374Y1301166D02*
Y1299276D01*
G01Y1308646D02*
Y1306757D01*
G01X981240Y1301166D02*
Y1299276D01*
G01Y1308646D02*
Y1306757D01*
G01X980792Y1301166D02*
Y1299276D01*
G01Y1308646D02*
Y1306757D01*
G01X980658Y1301166D02*
Y1299276D01*
G01Y1308646D02*
Y1306757D01*
G01X980464Y1301166D02*
Y1299276D01*
G01Y1308646D02*
Y1306757D01*
G01X979993Y1298056D02*
Y1309867D01*
G01X974481D02*
Y1298056D01*
G01X974010Y1304906D02*
Y1303017D01*
G01X973816Y1304906D02*
Y1303017D01*
G01X973682Y1304906D02*
Y1303017D01*
G01X973234Y1304906D02*
Y1303017D01*
G01X973100Y1304906D02*
Y1303017D01*
G01X972906Y1304906D02*
Y1303017D01*
G01X972316Y1304906D02*
Y1303017D01*
G01X950662Y1351796D02*
Y1349828D01*
G01Y1362951D02*
Y1360982D01*
G01Y1379355D02*
X950327Y1381324D01*
G01X950662Y1389526D02*
Y1387885D01*
G01Y1394775D02*
Y1393135D01*
G01Y1400024D02*
Y1398384D01*
G01Y1404289D02*
Y1402649D01*
G01Y1409539D02*
Y1407898D01*
G01Y1414788D02*
Y1413148D01*
G01X950327Y1377387D02*
X950662Y1379355D01*
G01X992394Y1816244D02*
Y1734079D01*
G01Y1816244D02*
Y1734079D01*
G01X973299Y1791953D02*
G03I-7874J0D01*
G01X973890D02*
G03I-8465J0D01*
G01X974284D02*
G03I-8859J0D01*
G01X974874D02*
G03I-9449J0D01*
G01X975169D02*
G03I-9744J0D01*
G01X975268D02*
G03I-9843J0D01*
G01D02*
G03I-9843J0D01*
G01X980583D02*
G03I-15158J0D01*
G01X988063Y1829630D02*
G03Y1816244I0J-6693D01*
G01Y1829630D02*
G03Y1816244I0J-6693D01*
G01X992394D02*
X988063D01*
G01X992394D02*
X988063D01*
G01X992394Y1814000D02*
X1003417D01*
G01X978969D02*
X992394D01*
G01X978969Y1831874D02*
Y1814000D01*
G01X982907Y1826363D02*
Y1819513D01*
G01X985569Y1823690D02*
X985752D01*
G01Y1822230D02*
X985569D01*
G01X986647Y1821678D02*
X989166D01*
G01X986647Y1824198D02*
Y1821678D01*
G01X985752Y1823690D02*
Y1822230D01*
G01X985569D02*
Y1823442D01*
G01X985387Y1823224D02*
Y1823473D01*
G01X985569Y1823442D02*
X985387Y1823224D01*
G01Y1823473D02*
X985569Y1823690D01*
G01X989166Y1824198D02*
X986647D01*
G01X989166Y1821678D02*
Y1824198D01*
G01X989875Y1822938D02*
G03I-1968J0D01*
G01X982907Y1819513D02*
X983816Y1817938D01*
G01X993816D02*
X1001997D01*
G01X983816D02*
X991997D01*
G01X992907Y1819513D02*
X993816Y1817938D01*
G01X991997D02*
X992907Y1819513D01*
G01X999166Y1821678D02*
Y1824198D01*
G01X999875Y1822938D02*
G03I-1968J0D01*
G01X999166Y1824198D02*
X996647D01*
G01Y1821678D02*
X999166D01*
G01X996647Y1824198D02*
Y1821678D01*
G01X973299Y1867150D02*
G03I-7874J0D01*
G01X973890D02*
G03I-8465J0D01*
G01X974284D02*
G03I-8859J0D01*
G01X974874D02*
G03I-9449J0D01*
G01X975169D02*
G03I-9744J0D01*
G01X975268D02*
G03I-9843J0D01*
G01D02*
G03I-9843J0D01*
G01X980583D02*
G03I-15158J0D01*
G01X992394Y1831874D02*
X978969D01*
G01X1003417D02*
X992394D01*
G01Y1829630D02*
X988063D01*
G01X992394D02*
X988063D01*
G01X992394Y1901008D02*
Y1829630D01*
G01Y1901008D02*
Y1829630D01*
G01X983816Y1827938D02*
X982907Y1826363D01*
G01X991997Y1827938D02*
X983816D01*
G01X1001997D02*
X993816D01*
G01X992907Y1826363D02*
X991997Y1827938D01*
G01X993816D02*
X992907Y1826363D01*
G01X1010110Y-65085D02*
Y-84022D01*
G01X1045938Y-33677D02*
X1037277D01*
X1043484Y-37683D01*
Y-32269D01*
G01X1044639Y-28697D02*
X1045361Y-28047D01*
X1045794Y-27289D01*
X1045938Y-26315D01*
X1045649Y-25341D01*
X1045072Y-24583D01*
X1044062Y-24041D01*
X1042907Y-23933D01*
X1041752Y-24150D01*
X1041030Y-24691D01*
X1040453Y-25449D01*
X1040308Y-26207D01*
X1040453Y-26965D01*
X1041030Y-27939D01*
X1037277Y-27614D01*
Y-24691D01*
G01X1046227Y-17654D02*
X1046082Y-17871D01*
X1045794D01*
X1045649Y-17654D01*
X1045794Y-17437D01*
X1046082D01*
X1046227Y-17654D01*
G01X1044639Y-11375D02*
X1045361Y-10725D01*
X1045794Y-9967D01*
X1045938Y-8993D01*
X1045649Y-8019D01*
X1045072Y-7261D01*
X1044062Y-6719D01*
X1042907Y-6611D01*
X1041752Y-6828D01*
X1041030Y-7369D01*
X1040453Y-8127D01*
X1040308Y-8885D01*
X1040453Y-9643D01*
X1041030Y-10617D01*
X1037277Y-10292D01*
Y-7369D01*
G01Y-332D02*
X1037566Y-1198D01*
X1038287Y-1848D01*
X1039153Y-2281D01*
X1040308Y-2606D01*
X1041608Y-2714D01*
X1042907Y-2606D01*
X1044062Y-2281D01*
X1044928Y-1848D01*
X1045649Y-1198D01*
X1045938Y-332D01*
X1045649Y534D01*
X1044928Y1184D01*
X1044062Y1617D01*
X1042907Y1942D01*
X1041608Y2050D01*
X1040308Y1942D01*
X1039153Y1617D01*
X1038287Y1184D01*
X1037566Y534D01*
X1037277Y-332D01*
G01X1054993Y122859D02*
G03I-6890J0D01*
G01X1063851D02*
G03I-15748J0D01*
G01X1023477Y183528D02*
G03I-4901J0D01*
G01X1024676Y163528D02*
G03I-6100J0D01*
G01X1024835D02*
G03I-6259J0D01*
G01X1032276Y153528D02*
Y189528D01*
G01D02*
Y190028D01*
G01X1024376Y194528D02*
Y187528D01*
G01X1019926Y188478D02*
Y178578D01*
G01X1017226D02*
Y188478D01*
G01X1007876Y187528D02*
Y349528D01*
G01X1004876Y153528D02*
Y383528D01*
G01X1003576Y152032D02*
Y385024D01*
G01X1032276Y189528D02*
X1062276D01*
G01X1017226Y188478D02*
X1019926D01*
G01X1024376Y187528D02*
X1007876D01*
G01X1004876Y183528D02*
X1032276D01*
G01X1062276Y182028D02*
X1032276D01*
G01X1019926Y178578D02*
X1017226D01*
G01X1004876Y153528D02*
X1032276D01*
G01X1063576Y152032D02*
X1003576D01*
G01X1050305Y227028D02*
G03X1046846I-1730J-1020D01*
G01X1046823Y215028D02*
G03X1050328I1752J980D01*
G01X1046823Y235028D02*
G03X1050328I1752J980D01*
G01X1046846Y227028D02*
G03X1050305I1730J-1020D01*
G01X1050328Y215028D02*
G03X1046823I-1753J980D01*
G01X1050328Y235028D02*
G03X1046823I-1753J980D01*
G01X1040305Y227028D02*
G03X1036846I-1730J-1020D01*
G01X1036823Y215028D02*
G03X1040328I1752J980D01*
G01X1036823Y235028D02*
G03X1040328I1752J980D01*
G01X1036846Y227028D02*
G03X1040305I1730J-1020D01*
G01X1040328Y215028D02*
G03X1036823I-1753J980D01*
G01X1040328Y235028D02*
G03X1036823I-1753J980D01*
G01X1030305Y227028D02*
G03X1026846I-1729J-1020D01*
G01X1026823Y215028D02*
G03X1030328I1753J980D01*
G01X1026823Y235028D02*
G03X1030328I1753J980D01*
G01X1026846Y227028D02*
G03X1030305I1730J-1020D01*
G01X1030328Y215028D02*
G03X1026823I-1753J980D01*
G01X1030328Y235028D02*
G03X1026823I-1753J980D01*
G01X1050305Y207028D02*
G03X1046846I-1730J-1020D01*
G01X1040305D02*
G03X1036846I-1730J-1020D01*
G01X1030305D02*
G03X1026846I-1729J-1020D01*
G01X1046846D02*
G03X1050305I1730J-1020D01*
G01X1036846D02*
G03X1040305I1730J-1020D01*
G01X1026846D02*
G03X1030305I1730J-1020D01*
G01X1020305D02*
G03X1016846I-1730J-1020D01*
G01X1020305Y227028D02*
G03X1016846I-1730J-1020D01*
G01X1016823Y215028D02*
G03X1020328I1752J980D01*
G01X1016823Y235028D02*
G03X1020328I1752J980D01*
G01X1016846Y207028D02*
G03X1020305I1729J-1020D01*
G01X1016846Y227028D02*
G03X1020305I1729J-1020D01*
G01X1020328Y215028D02*
G03X1016823I-1753J980D01*
G01X1020328Y235028D02*
G03X1016823I-1753J980D01*
G01X1051206Y215028D02*
Y207028D01*
G01Y235028D02*
Y227028D01*
G01X1049826Y235028D02*
Y237028D01*
G01Y225028D02*
Y227028D01*
G01Y215028D02*
Y217028D01*
G01Y205028D02*
Y207028D01*
G01X1047326D02*
Y205028D01*
G01Y217028D02*
Y215028D01*
G01Y227028D02*
Y225028D01*
G01Y237028D02*
Y235028D01*
G01X1047281Y207028D02*
Y205028D01*
G01Y217028D02*
Y215028D01*
G01Y227028D02*
Y225028D01*
G01Y237028D02*
Y235028D01*
G01X1042488Y207028D02*
Y205028D01*
G01Y217028D02*
Y215028D01*
G01Y227028D02*
Y225028D01*
G01Y237028D02*
Y235028D01*
G01X1039826D02*
Y237028D01*
G01Y225028D02*
Y227028D01*
G01Y215028D02*
Y217028D01*
G01Y205028D02*
Y207028D01*
G01X1037326D02*
Y205028D01*
G01Y217028D02*
Y215028D01*
G01Y227028D02*
Y225028D01*
G01Y237028D02*
Y235028D01*
G01X1029826D02*
Y237028D01*
G01Y225028D02*
Y227028D01*
G01Y215028D02*
Y217028D01*
G01Y205028D02*
Y207028D01*
G01X1027326D02*
Y205028D01*
G01Y217028D02*
Y215028D01*
G01Y227028D02*
Y225028D01*
G01Y237028D02*
Y235028D01*
G01X1021213Y207028D02*
Y205028D01*
G01Y217028D02*
Y215028D01*
G01Y227028D02*
Y225028D01*
G01Y237028D02*
Y235028D01*
G01X1019826D02*
Y237028D01*
G01Y225028D02*
Y227028D01*
G01Y215028D02*
Y217028D01*
G01Y205028D02*
Y207028D01*
G01X1017326D02*
Y205028D01*
G01Y217028D02*
Y215028D01*
G01Y227028D02*
Y225028D01*
G01Y237028D02*
Y235028D01*
G01X1016420D02*
Y237028D01*
G01Y225028D02*
Y227028D01*
G01Y215028D02*
Y217028D01*
G01Y205028D02*
Y207028D01*
G01X1015806Y227028D02*
Y235028D01*
G01Y207028D02*
Y215028D01*
G01X1009876Y198528D02*
Y243528D01*
G01X1016420Y237028D02*
X1047281D01*
G01X1049826D02*
X1047326D01*
G01X1015806Y235028D02*
X1051206D01*
G01X1015806Y227028D02*
X1051206D01*
G01X1047326Y225028D02*
X1049826D01*
G01X1016420D02*
X1047281D01*
G01X1016420Y217028D02*
X1047281D01*
G01X1049826D02*
X1047326D01*
G01X1015806Y215028D02*
X1051206D01*
G01X1015806Y207028D02*
X1051206D01*
G01X1047326Y205028D02*
X1049826D01*
G01X1016420D02*
X1047281D01*
G01X1007876Y198528D02*
X1059276D01*
G01Y194528D02*
X1024376D01*
G01X1032276Y190028D02*
X1062276D01*
G01X1050583Y278528D02*
G03I-2007J0D01*
G01Y288528D02*
G03I-2007J0D01*
G01X1040583Y278528D02*
G03I-2007J0D01*
G01Y288528D02*
G03I-2007J0D01*
G01X1050583Y248528D02*
G03I-2007J0D01*
G01Y258528D02*
G03I-2007J0D01*
G01Y268528D02*
G03I-2007J0D01*
G01X1040583Y248528D02*
G03I-2007J0D01*
G01Y258528D02*
G03I-2007J0D01*
G01Y268528D02*
G03I-2007J0D01*
G01X1030583Y278528D02*
G03I-2007J0D01*
G01Y288528D02*
G03I-2007J0D01*
G01Y248528D02*
G03I-2007J0D01*
G01Y258528D02*
G03I-2007J0D01*
G01Y268528D02*
G03I-2007J0D01*
G01X1020583Y248528D02*
G03I-2007J0D01*
G01Y258528D02*
G03I-2007J0D01*
G01Y268528D02*
G03I-2007J0D01*
G01Y278528D02*
G03I-2007J0D01*
G01Y288528D02*
G03I-2007J0D01*
G01X1049826Y249778D02*
X1050216Y250169D01*
G01X1047326Y247278D02*
X1046935Y246888D01*
G01X1049826Y259778D02*
X1050216Y260169D01*
G01X1036935Y246888D02*
X1037326Y247278D01*
G01X1040216Y250169D02*
X1039826Y249778D01*
G01X1047326Y257278D02*
X1046935Y256888D01*
G01X1049826Y269778D02*
X1050216Y270169D01*
G01X1036935Y256888D02*
X1037326Y257278D01*
G01X1026935Y246888D02*
X1027326Y247278D01*
G01X1030216Y250169D02*
X1029826Y249778D01*
G01X1040216Y260169D02*
X1039826Y259778D01*
G01X1047326Y267278D02*
X1046935Y266888D01*
G01X1049826Y279778D02*
X1050216Y280169D01*
G01X1036935Y266888D02*
X1037326Y267278D01*
G01X1026935Y256888D02*
X1027326Y257278D01*
G01X1016935Y246888D02*
X1017326Y247278D01*
G01X1020216Y250169D02*
X1019826Y249778D01*
G01X1030216Y260169D02*
X1029826Y259778D01*
G01X1040216Y270169D02*
X1039826Y269778D01*
G01X1047326Y277278D02*
X1046935Y276888D01*
G01X1049826Y289778D02*
X1050216Y290169D01*
G01X1036935Y276888D02*
X1037326Y277278D01*
G01X1026935Y266888D02*
X1027326Y267278D01*
G01X1016935Y256888D02*
X1017326Y257278D01*
G01X1020216Y260169D02*
X1019826Y259778D01*
G01X1030216Y270169D02*
X1029826Y269778D01*
G01X1040216Y280169D02*
X1039826Y279778D01*
G01X1047326Y287278D02*
X1046935Y286888D01*
G01X1036935D02*
X1037326Y287278D01*
G01X1026935Y276888D02*
X1027326Y277278D01*
G01X1016935Y266888D02*
X1017326Y267278D01*
G01X1020216Y270169D02*
X1019826Y269778D01*
G01X1030216Y280169D02*
X1029826Y279778D01*
G01X1040216Y290169D02*
X1039826Y289778D01*
G01X1026935Y286888D02*
X1027326Y287278D01*
G01X1016935Y276888D02*
X1017326Y277278D01*
G01X1020216Y280169D02*
X1019826Y279778D01*
G01X1030216Y290169D02*
X1029826Y289778D01*
G01X1016935Y286888D02*
X1017326Y287278D01*
G01X1020216Y290169D02*
X1019826Y289778D01*
G01X1050216Y286888D02*
Y290169D01*
G01Y276888D02*
Y280169D01*
G01Y266888D02*
Y270169D01*
G01Y256888D02*
Y260169D01*
G01Y246888D02*
Y250169D01*
G01X1049956Y249908D02*
Y247148D01*
G01Y259908D02*
Y257148D01*
G01Y269908D02*
Y267148D01*
G01Y279908D02*
Y277148D01*
G01Y289908D02*
Y287148D01*
G01X1049826Y249778D02*
Y247278D01*
G01Y259778D02*
Y257278D01*
G01Y269778D02*
Y267278D01*
G01Y279778D02*
Y277278D01*
G01Y289778D02*
Y287278D01*
G01X1047326Y249778D02*
Y247278D01*
G01Y259778D02*
Y257278D01*
G01Y269778D02*
Y267278D01*
G01Y279778D02*
Y277278D01*
G01Y289778D02*
Y287278D01*
G01X1047196Y249908D02*
Y247148D01*
G01Y259908D02*
Y257148D01*
G01Y269908D02*
Y267148D01*
G01Y279908D02*
Y277148D01*
G01Y289908D02*
Y287148D01*
G01X1046935Y250169D02*
Y246888D01*
G01Y260169D02*
Y256888D01*
G01Y270169D02*
Y266888D01*
G01Y280169D02*
Y276888D01*
G01Y290169D02*
Y286888D01*
G01X1040216Y250169D02*
Y246888D01*
G01Y260169D02*
Y256888D01*
G01Y270169D02*
Y266888D01*
G01Y280169D02*
Y276888D01*
G01Y290169D02*
Y286888D01*
G01X1039956Y249908D02*
Y247148D01*
G01Y259908D02*
Y257148D01*
G01Y269908D02*
Y267148D01*
G01Y279908D02*
Y277148D01*
G01Y289908D02*
Y287148D01*
G01X1039826Y249778D02*
Y247278D01*
G01Y259778D02*
Y257278D01*
G01Y269778D02*
Y267278D01*
G01Y279778D02*
Y277278D01*
G01Y289778D02*
Y287278D01*
G01X1037326D02*
Y289778D01*
G01Y277278D02*
Y279778D01*
G01Y267278D02*
Y269778D01*
G01Y257278D02*
Y259778D01*
G01Y247278D02*
Y249778D01*
G01X1037196Y287148D02*
Y289908D01*
G01Y277148D02*
Y279908D01*
G01Y267148D02*
Y269908D01*
G01Y257148D02*
Y259908D01*
G01Y247148D02*
Y249908D01*
G01X1036935Y286888D02*
Y290169D01*
G01Y276888D02*
Y280169D01*
G01Y266888D02*
Y270169D01*
G01Y256888D02*
Y260169D01*
G01Y246888D02*
Y250169D01*
G01X1030216D02*
Y246888D01*
G01Y260169D02*
Y256888D01*
G01Y270169D02*
Y266888D01*
G01Y280169D02*
Y276888D01*
G01Y290169D02*
Y286888D01*
G01X1029956Y249908D02*
Y247148D01*
G01Y259908D02*
Y257148D01*
G01Y269908D02*
Y267148D01*
G01Y279908D02*
Y277148D01*
G01Y289908D02*
Y287148D01*
G01X1029826Y249778D02*
Y247278D01*
G01Y259778D02*
Y257278D01*
G01Y269778D02*
Y267278D01*
G01Y279778D02*
Y277278D01*
G01Y289778D02*
Y287278D01*
G01X1027326D02*
Y289778D01*
G01Y277278D02*
Y279778D01*
G01Y267278D02*
Y269778D01*
G01Y257278D02*
Y259778D01*
G01Y247278D02*
Y249778D01*
G01X1027196Y287148D02*
Y289908D01*
G01Y277148D02*
Y279908D01*
G01Y267148D02*
Y269908D01*
G01Y257148D02*
Y259908D01*
G01Y247148D02*
Y249908D01*
G01X1026935Y286888D02*
Y290169D01*
G01Y276888D02*
Y280169D01*
G01Y266888D02*
Y270169D01*
G01Y256888D02*
Y260169D01*
G01Y246888D02*
Y250169D01*
G01X1020216D02*
Y246888D01*
G01Y260169D02*
Y256888D01*
G01Y270169D02*
Y266888D01*
G01Y280169D02*
Y276888D01*
G01Y290169D02*
Y286888D01*
G01X1019956Y249908D02*
Y247148D01*
G01Y259908D02*
Y257148D01*
G01Y269908D02*
Y267148D01*
G01Y279908D02*
Y277148D01*
G01Y289908D02*
Y287148D01*
G01X1019826Y249778D02*
Y247278D01*
G01Y259778D02*
Y257278D01*
G01Y269778D02*
Y267278D01*
G01Y279778D02*
Y277278D01*
G01Y289778D02*
Y287278D01*
G01X1017326D02*
Y289778D01*
G01Y277278D02*
Y279778D01*
G01Y267278D02*
Y269778D01*
G01Y257278D02*
Y259778D01*
G01Y247278D02*
Y249778D01*
G01X1017196Y287148D02*
Y289908D01*
G01Y277148D02*
Y279908D01*
G01Y267148D02*
Y269908D01*
G01Y257148D02*
Y259908D01*
G01Y247148D02*
Y249908D01*
G01X1016935Y286888D02*
Y290169D01*
G01Y276888D02*
Y280169D01*
G01Y266888D02*
Y270169D01*
G01Y256888D02*
Y260169D01*
G01Y246888D02*
Y250169D01*
G01X1010076Y243528D02*
Y293528D01*
G01X1049826Y287278D02*
X1050216Y286888D01*
G01X1046935Y290169D02*
X1047326Y289778D01*
G01X1049826Y277278D02*
X1050216Y276888D01*
G01X1046935Y280169D02*
X1047326Y279778D01*
G01X1039826Y287278D02*
X1040216Y286888D01*
G01X1036935Y290169D02*
X1037326Y289778D01*
G01X1049826Y267278D02*
X1050216Y266888D01*
G01X1046935Y270169D02*
X1047326Y269778D01*
G01X1039826Y277278D02*
X1040216Y276888D01*
G01X1036935Y280169D02*
X1037326Y279778D01*
G01X1029826Y287278D02*
X1030216Y286888D01*
G01X1026935Y290169D02*
X1027326Y289778D01*
G01X1049826Y257278D02*
X1050216Y256888D01*
G01X1046935Y260169D02*
X1047326Y259778D01*
G01X1039826Y267278D02*
X1040216Y266888D01*
G01X1036935Y270169D02*
X1037326Y269778D01*
G01X1029826Y277278D02*
X1030216Y276888D01*
G01X1026935Y280169D02*
X1027326Y279778D01*
G01X1019826Y287278D02*
X1020216Y286888D01*
G01X1016935Y290169D02*
X1017326Y289778D01*
G01X1049826Y247278D02*
X1050216Y246888D01*
G01X1046935Y250169D02*
X1047326Y249778D01*
G01X1039826Y257278D02*
X1040216Y256888D01*
G01X1036935Y260169D02*
X1037326Y259778D01*
G01X1029826Y267278D02*
X1030216Y266888D01*
G01X1026935Y270169D02*
X1027326Y269778D01*
G01X1019826Y277278D02*
X1020216Y276888D01*
G01X1016935Y280169D02*
X1017326Y279778D01*
G01X1039826Y247278D02*
X1040216Y246888D01*
G01X1036935Y250169D02*
X1037326Y249778D01*
G01X1029826Y257278D02*
X1030216Y256888D01*
G01X1026935Y260169D02*
X1027326Y259778D01*
G01X1019826Y267278D02*
X1020216Y266888D01*
G01X1016935Y270169D02*
X1017326Y269778D01*
G01X1029826Y247278D02*
X1030216Y246888D01*
G01X1026935Y250169D02*
X1027326Y249778D01*
G01X1019826Y257278D02*
X1020216Y256888D01*
G01X1016935Y260169D02*
X1017326Y259778D01*
G01X1019826Y247278D02*
X1020216Y246888D01*
G01X1016935Y250169D02*
X1017326Y249778D01*
G01X1036935Y290169D02*
X1040216D01*
G01X1026935D02*
X1030216D01*
G01X1016935D02*
X1020216D01*
G01X1050216D02*
X1046935D01*
G01X1047196Y289908D02*
X1049956D01*
G01X1037196D02*
X1039956D01*
G01X1027196D02*
X1029956D01*
G01X1017196D02*
X1019956D01*
G01X1047326Y289778D02*
X1049826D01*
G01X1037326D02*
X1039826D01*
G01X1027326D02*
X1029826D01*
G01X1017326D02*
X1019826D01*
G01Y287278D02*
X1017326D01*
G01X1029826D02*
X1027326D01*
G01X1039826D02*
X1037326D01*
G01X1049826D02*
X1047326D01*
G01X1019956Y287148D02*
X1017196D01*
G01X1029956D02*
X1027196D01*
G01X1039956D02*
X1037196D01*
G01X1049956D02*
X1047196D01*
G01X1046935Y286888D02*
X1050216D01*
G01X1020216D02*
X1016935D01*
G01X1030216D02*
X1026935D01*
G01X1040216D02*
X1036935D01*
G01Y280169D02*
X1040216D01*
G01X1026935D02*
X1030216D01*
G01X1016935D02*
X1020216D01*
G01X1050216D02*
X1046935D01*
G01X1047196Y279908D02*
X1049956D01*
G01X1037196D02*
X1039956D01*
G01X1027196D02*
X1029956D01*
G01X1017196D02*
X1019956D01*
G01X1047326Y279778D02*
X1049826D01*
G01X1037326D02*
X1039826D01*
G01X1027326D02*
X1029826D01*
G01X1017326D02*
X1019826D01*
G01Y277278D02*
X1017326D01*
G01X1029826D02*
X1027326D01*
G01X1039826D02*
X1037326D01*
G01X1049826D02*
X1047326D01*
G01X1019956Y277148D02*
X1017196D01*
G01X1029956D02*
X1027196D01*
G01X1039956D02*
X1037196D01*
G01X1049956D02*
X1047196D01*
G01X1046935Y276888D02*
X1050216D01*
G01X1020216D02*
X1016935D01*
G01X1030216D02*
X1026935D01*
G01X1040216D02*
X1036935D01*
G01Y270169D02*
X1040216D01*
G01X1026935D02*
X1030216D01*
G01X1016935D02*
X1020216D01*
G01X1050216D02*
X1046935D01*
G01X1047196Y269908D02*
X1049956D01*
G01X1037196D02*
X1039956D01*
G01X1027196D02*
X1029956D01*
G01X1017196D02*
X1019956D01*
G01X1047326Y269778D02*
X1049826D01*
G01X1037326D02*
X1039826D01*
G01X1027326D02*
X1029826D01*
G01X1017326D02*
X1019826D01*
G01Y267278D02*
X1017326D01*
G01X1029826D02*
X1027326D01*
G01X1039826D02*
X1037326D01*
G01X1049826D02*
X1047326D01*
G01X1019956Y267148D02*
X1017196D01*
G01X1029956D02*
X1027196D01*
G01X1039956D02*
X1037196D01*
G01X1049956D02*
X1047196D01*
G01X1046935Y266888D02*
X1050216D01*
G01X1020216D02*
X1016935D01*
G01X1030216D02*
X1026935D01*
G01X1040216D02*
X1036935D01*
G01Y260169D02*
X1040216D01*
G01X1026935D02*
X1030216D01*
G01X1016935D02*
X1020216D01*
G01X1050216D02*
X1046935D01*
G01X1047196Y259908D02*
X1049956D01*
G01X1037196D02*
X1039956D01*
G01X1027196D02*
X1029956D01*
G01X1017196D02*
X1019956D01*
G01X1047326Y259778D02*
X1049826D01*
G01X1037326D02*
X1039826D01*
G01X1027326D02*
X1029826D01*
G01X1017326D02*
X1019826D01*
G01Y257278D02*
X1017326D01*
G01X1029826D02*
X1027326D01*
G01X1039826D02*
X1037326D01*
G01X1049826D02*
X1047326D01*
G01X1019956Y257148D02*
X1017196D01*
G01X1029956D02*
X1027196D01*
G01X1039956D02*
X1037196D01*
G01X1049956D02*
X1047196D01*
G01X1046935Y256888D02*
X1050216D01*
G01X1020216D02*
X1016935D01*
G01X1030216D02*
X1026935D01*
G01X1040216D02*
X1036935D01*
G01Y250169D02*
X1040216D01*
G01X1026935D02*
X1030216D01*
G01X1016935D02*
X1020216D01*
G01X1050216D02*
X1046935D01*
G01X1047196Y249908D02*
X1049956D01*
G01X1037196D02*
X1039956D01*
G01X1027196D02*
X1029956D01*
G01X1017196D02*
X1019956D01*
G01X1047326Y249778D02*
X1049826D01*
G01X1037326D02*
X1039826D01*
G01X1027326D02*
X1029826D01*
G01X1017326D02*
X1019826D01*
G01Y247278D02*
X1017326D01*
G01X1029826D02*
X1027326D01*
G01X1039826D02*
X1037326D01*
G01X1049826D02*
X1047326D01*
G01X1019956Y247148D02*
X1017196D01*
G01X1029956D02*
X1027196D01*
G01X1039956D02*
X1037196D01*
G01X1049956D02*
X1047196D01*
G01X1046935Y246888D02*
X1050216D01*
G01X1020216D02*
X1016935D01*
G01X1030216D02*
X1026935D01*
G01X1040216D02*
X1036935D01*
G01X1007880Y243528D02*
X1010076D01*
G01X1050328Y322029D02*
G03X1046823I-1753J-981D01*
G01X1046846Y310028D02*
G03X1050305I1730J1020D01*
G01X1046846Y330028D02*
G03X1050305I1730J1020D01*
G01X1046823Y322029D02*
G03X1050328I1752J-981D01*
G01X1050305Y310028D02*
G03X1046846I-1730J1020D01*
G01X1050305Y330028D02*
G03X1046846I-1730J1020D01*
G01X1050328Y302029D02*
G03X1046823I-1753J-981D01*
G01D02*
G03X1050328I1752J-981D01*
G01X1040328Y322029D02*
G03X1036823I-1753J-981D01*
G01X1036846Y310028D02*
G03X1040305I1730J1020D01*
G01X1036846Y330028D02*
G03X1040305I1730J1020D01*
G01X1036823Y322029D02*
G03X1040328I1752J-981D01*
G01X1040305Y310028D02*
G03X1036846I-1730J1020D01*
G01X1040305Y330028D02*
G03X1036846I-1730J1020D01*
G01X1040328Y302029D02*
G03X1036823I-1753J-981D01*
G01D02*
G03X1040328I1752J-981D01*
G01X1030328D02*
G03X1026823I-1753J-981D01*
G01X1030328Y322029D02*
G03X1026823I-1753J-981D01*
G01X1026846Y310028D02*
G03X1030305I1730J1020D01*
G01X1026846Y330028D02*
G03X1030305I1730J1020D01*
G01X1026823Y302029D02*
G03X1030328I1753J-981D01*
G01X1026823Y322029D02*
G03X1030328I1753J-981D01*
G01X1030305Y310028D02*
G03X1026846I-1729J1020D01*
G01X1030305Y330028D02*
G03X1026846I-1729J1020D01*
G01X1020328Y302029D02*
G03X1016823I-1753J-981D01*
G01X1020328Y322029D02*
G03X1016823I-1753J-981D01*
G01X1016846Y310028D02*
G03X1020305I1729J1020D01*
G01X1016846Y330028D02*
G03X1020305I1729J1020D01*
G01X1016823Y302029D02*
G03X1020328I1752J-981D01*
G01X1016823Y322029D02*
G03X1020328I1752J-981D01*
G01X1020305Y310028D02*
G03X1016846I-1730J1020D01*
G01X1020305Y330028D02*
G03X1016846I-1730J1020D01*
G01X1021713Y330875D02*
X1021638Y330850D01*
G01Y330998D02*
X1021713Y331022D01*
G01X1021814Y330949D02*
X1021713Y330875D01*
G01Y331022D02*
X1021763Y331072D01*
G01X1021889Y331047D02*
X1021814Y330949D01*
G01X1021763Y331072D02*
X1021789Y331145D01*
G01X1021914Y331170D02*
X1021889Y331047D01*
G01X1051206Y310028D02*
Y302028D01*
G01Y330028D02*
Y322028D01*
G01X1049826Y330028D02*
Y332028D01*
G01Y320028D02*
Y322028D01*
G01Y310028D02*
Y312028D01*
G01Y300028D02*
Y302028D01*
G01X1047326D02*
Y300028D01*
G01Y312028D02*
Y310028D01*
G01Y322028D02*
Y320028D01*
G01Y332028D02*
Y330028D01*
G01X1047281Y302028D02*
Y300028D01*
G01Y312028D02*
Y310028D01*
G01Y322028D02*
Y320028D01*
G01Y332028D02*
Y330028D01*
G01X1042488Y302028D02*
Y300028D01*
G01Y312028D02*
Y310028D01*
G01Y322028D02*
Y320028D01*
G01Y332028D02*
Y330028D01*
G01X1039826D02*
Y332028D01*
G01Y320028D02*
Y322028D01*
G01Y310028D02*
Y312028D01*
G01Y300028D02*
Y302028D01*
G01X1037326D02*
Y300028D01*
G01Y312028D02*
Y310028D01*
G01Y322028D02*
Y320028D01*
G01Y332028D02*
Y330028D01*
G01X1029826D02*
Y332028D01*
G01Y320028D02*
Y322028D01*
G01Y310028D02*
Y312028D01*
G01Y300028D02*
Y302028D01*
G01X1027326D02*
Y300028D01*
G01Y312028D02*
Y310028D01*
G01Y322028D02*
Y320028D01*
G01Y332028D02*
Y330028D01*
G01X1024376Y349528D02*
Y342528D01*
G01X1021914Y330506D02*
Y330358D01*
G01Y331761D02*
Y331170D01*
G01X1021789Y331145D02*
Y331613D01*
G01X1021412D02*
Y331145D01*
G01X1021261Y331170D02*
Y331613D01*
G01X1021213Y302028D02*
Y300028D01*
G01Y312028D02*
Y310028D01*
G01Y322028D02*
Y320028D01*
G01Y332028D02*
Y330028D01*
G01X1020733Y331613D02*
Y331761D01*
G01Y330358D02*
Y330506D01*
G01X1019826Y330028D02*
Y332028D01*
G01Y320028D02*
Y322028D01*
G01Y310028D02*
Y312028D01*
G01Y300028D02*
Y302028D01*
G01X1017326D02*
Y300028D01*
G01Y312028D02*
Y310028D01*
G01Y322028D02*
Y320028D01*
G01Y332028D02*
Y330028D01*
G01X1016420D02*
Y332028D01*
G01Y320028D02*
Y322028D01*
G01Y310028D02*
Y312028D01*
G01Y300028D02*
Y302028D01*
G01X1015806Y322028D02*
Y330028D01*
G01Y302028D02*
Y310028D01*
G01X1009876Y293528D02*
Y338528D01*
G01X1021286Y331047D02*
X1021261Y331170D01*
G01X1021412Y331145D02*
X1021437Y331072D01*
G01X1021361Y330949D02*
X1021286Y331047D01*
G01X1021437Y331072D02*
X1021487Y331022D01*
G01X1021738Y330653D02*
X1021914Y330506D01*
G01X1021713D02*
X1021537Y330653D01*
G01X1021462Y330875D02*
X1021361Y330949D01*
G01X1021487Y331022D02*
X1021562Y330998D01*
G01X1021537Y330850D02*
X1021462Y330875D01*
G01X1024376Y342528D02*
X1059276D01*
G01X1007876Y338528D02*
X1059276D01*
G01X1016420Y332028D02*
X1047281D01*
G01X1049826D02*
X1047326D01*
G01X1020733Y331761D02*
X1021914D01*
G01X1021261Y331613D02*
X1020733D01*
G01X1021789D02*
X1021412D01*
G01X1021562Y330998D02*
X1021638D01*
G01Y330850D02*
X1021537D01*
G01Y330653D02*
X1021738D01*
G01X1020733Y330506D02*
X1021713D01*
G01X1021914Y330358D02*
X1020733D01*
G01X1015806Y330028D02*
X1051206D01*
G01X1015806Y322028D02*
X1051206D01*
G01X1047326Y320028D02*
X1049826D01*
G01X1016420D02*
X1047281D01*
G01X1016420Y312028D02*
X1047281D01*
G01X1049826D02*
X1047326D01*
G01X1015806Y310028D02*
X1051206D01*
G01X1015806Y302028D02*
X1051206D01*
G01X1047326Y300028D02*
X1049826D01*
G01X1016420D02*
X1047281D01*
G01X1007880Y293528D02*
X1010076D01*
G01X1023477Y353528D02*
G03I-4901J0D01*
G01X1024676Y373528D02*
G03I-6100J0D01*
G01X1024835D02*
G03I-6259J0D01*
G01X1032276Y347528D02*
Y383528D01*
G01Y347028D02*
Y347528D01*
G01X1019926Y358478D02*
Y348578D01*
G01X1017226D02*
Y358478D01*
G01X1003576Y385024D02*
X1063576D01*
G01X1032276Y383528D02*
X1004876D01*
G01X1017226Y358478D02*
X1019926D01*
G01X1032276Y355028D02*
X1062276D01*
G01X1032276Y353528D02*
X1004876D01*
G01X1007876Y349528D02*
X1024376D01*
G01X1019926Y348578D02*
X1017226D01*
G01X1062276Y347528D02*
X1032276D01*
G01X1062276Y347028D02*
X1032276D01*
G01X1054993Y614985D02*
G03I-6890J0D01*
G01X1063851D02*
G03I-15748J0D01*
G01X1016607Y954552D02*
Y949631D01*
G01Y982439D02*
Y977518D01*
G01X1002367Y1006225D02*
X1004880Y1004585D01*
G01X1016607Y1046415D02*
X1015769Y1050517D01*
G01X1012419Y1047236D02*
X1011581Y1049696D01*
G01X1015769Y1050517D02*
X1013256Y1054618D01*
G01X1011581Y1049696D02*
X1009906Y1052157D01*
G01X1013256Y1054618D02*
X1009906Y1057078D01*
G01Y1052157D02*
X1007393Y1053797D01*
G01X1009906Y1057078D02*
X1005718Y1058719D01*
G01X1007393Y1053797D02*
X1004880Y1054618D01*
G01X1005718Y1058719D02*
X1001529D01*
G01X1004880Y1054618D02*
X1002367D01*
G01X1005718Y1030011D02*
X1009906Y1031652D01*
G01X1007393Y1034933D02*
X1009906Y1036573D01*
G01Y1031652D02*
X1013256Y1034112D01*
G01X1009906Y1036573D02*
X1011581Y1039034D01*
G01X1013256Y1034112D02*
X1015769Y1038213D01*
G01X1011581Y1039034D02*
X1012419Y1041494D01*
G01X1015769Y1038213D02*
X1016607Y1042314D01*
G01D02*
Y1046415D01*
G01Y1022629D02*
Y1017708D01*
G01X1012419Y1041494D02*
Y1047236D01*
G01X1002367Y1034112D02*
X1004880D01*
G01D02*
X1007393Y1034933D01*
G01X1016607Y1069381D02*
Y1065280D01*
G01Y1082505D02*
Y1078404D01*
G01Y1095628D02*
Y1091527D01*
G01Y1106291D02*
Y1102190D01*
G01Y1119414D02*
Y1115313D01*
G01Y1132538D02*
Y1128436D01*
G01X1054993Y1205536D02*
G03I-6890J0D01*
G01X1063851D02*
G03I-15748J0D01*
G01X1055780Y1372859D02*
G03I-7874J0D01*
G01X1056371D02*
G03I-8465J0D01*
G01X1056765D02*
G03I-8859J0D01*
G01X1057355D02*
G03I-9449J0D01*
G01X1057749D02*
G03I-9843J0D01*
G01X1063064D02*
G03I-15158J0D01*
G01X1063654D02*
G03I-15748J0D01*
G01X1066607D02*
G03I-18701J0D01*
G01X1042395Y1339985D02*
G03Y1405733I0J32874D01*
G01Y1339985D02*
X1021332D01*
G01D02*
Y1318922D01*
G01Y1405733D02*
X1042395D01*
G01X1021332Y1426796D02*
Y1405733D01*
G01X1057354Y1734079D02*
X1003417D01*
G01X1057354D02*
X1003417D01*
G01D02*
Y1816244D01*
G01Y1734079D02*
Y1816244D01*
G01X1049087Y1791953D02*
G03I-18701J0D01*
G01X1007748Y1816244D02*
G03Y1829630I0J6693D01*
G01Y1816244D02*
G03Y1829630I0J6693D01*
G01X1003417Y1816244D02*
X1007748D01*
G01X1003417D02*
X1007748D01*
G01X1003417Y1814000D02*
X1016843D01*
G01D02*
Y1831874D01*
G01X1038260Y1791953D02*
G03I-7874J0D01*
G01X1038850D02*
G03I-8464J0D01*
G01X1039244D02*
G03I-8858J0D01*
G01X1039835D02*
G03I-9449J0D01*
G01X1040130D02*
G03I-9744J0D01*
G01X1040228D02*
G03I-9842J0D01*
G01D02*
G03I-9842J0D01*
G01X1045543D02*
G03I-15157J0D01*
G01X1046134D02*
G03I-15748J0D01*
G01X1009875Y1822938D02*
G03I-1968J0D01*
G01X1002907Y1819513D02*
X1003816Y1817938D01*
G01X1001997D02*
X1002907Y1819513D01*
G01X1003816Y1817938D02*
X1011997D01*
G01X1009166Y1821678D02*
Y1824198D01*
G01D02*
X1006647D01*
G01Y1821678D02*
X1009166D01*
G01X1006647Y1824198D02*
Y1821678D01*
G01X1011997Y1817938D02*
X1012907Y1819513D01*
G01D02*
Y1826363D01*
G01X1011289Y1822626D02*
X1011562Y1822514D01*
G01X1010523Y1821285D02*
X1010304Y1821340D01*
G01X1011125Y1823575D02*
X1010851Y1823631D01*
G01X1010304Y1821620D02*
X1010578Y1821564D01*
G01X1011179Y1822458D02*
X1010851Y1822514D01*
G01X1010796Y1823911D02*
X1011179Y1823855D01*
G01X1010687Y1823911D02*
X1010796D01*
G01X1010851Y1823631D02*
X1010632D01*
G01X1010085Y1823296D02*
X1009812D01*
G01X1010632Y1822737D02*
X1010851D01*
G01Y1822514D02*
X1010632D01*
G01X1009757Y1821899D02*
X1010031D01*
G01X1010578Y1821564D02*
X1010906D01*
G01X1010961Y1821285D02*
X1010523D01*
G01X1010304Y1823855D02*
X1010687Y1823911D01*
G01X1010632Y1823631D02*
X1010359Y1823575D01*
G01X1010906Y1821564D02*
X1011179Y1821620D01*
G01Y1821340D02*
X1010961Y1821285D01*
G01X1011289Y1823464D02*
X1011125Y1823575D01*
G01X1011344Y1822346D02*
X1011179Y1822458D01*
G01X1010085Y1821452D02*
X1009921Y1821564D01*
G01X1011179Y1823855D02*
X1011398Y1823743D01*
G01X1010195Y1821676D02*
X1010304Y1821620D01*
G01Y1821340D02*
X1010085Y1821452D01*
G01X1011398Y1823743D02*
X1011617Y1823520D01*
G01X1010085Y1821787D02*
X1010195Y1821676D01*
G01X1011398Y1823296D02*
X1011289Y1823464D01*
G01X1011562Y1822514D02*
X1011672Y1822346D01*
G01X1009921Y1821564D02*
X1009812Y1821732D01*
G01X1011453Y1822123D02*
X1011344Y1822346D01*
G01X1010031Y1821899D02*
X1010085Y1821787D01*
G01X1009812Y1821732D02*
X1009757Y1821899D01*
G01X1011617Y1823520D02*
X1011672Y1823296D01*
G01Y1822346D02*
X1011726Y1822123D01*
G01D02*
Y1821899D01*
G01X1011672Y1823296D02*
Y1823184D01*
G01X1011453Y1821899D02*
Y1822123D01*
G01X1011398Y1823184D02*
Y1823296D01*
G01X1010632Y1822514D02*
Y1822737D01*
G01X1011672Y1823184D02*
X1011617Y1822961D01*
G01X1009812Y1823296D02*
X1009866Y1823520D01*
G01X1011726Y1821899D02*
X1011672Y1821732D01*
G01X1011398Y1821787D02*
X1011453Y1821899D01*
G01X1011289Y1822961D02*
X1011398Y1823184D01*
G01X1011672Y1821732D02*
X1011562Y1821564D01*
G01X1011617Y1822961D02*
X1011508Y1822793D01*
G01X1010195Y1823464D02*
X1010085Y1823296D01*
G01X1011289Y1821676D02*
X1011398Y1821787D01*
G01X1011179Y1822849D02*
X1011289Y1822961D01*
G01X1009866Y1823520D02*
X1010085Y1823743D01*
G01X1011562Y1821564D02*
X1011398Y1821452D01*
G01X1010359Y1823575D02*
X1010195Y1823464D01*
G01X1011508Y1822793D02*
X1011289Y1822626D01*
G01X1011398Y1821452D02*
X1011179Y1821340D01*
G01Y1821620D02*
X1011289Y1821676D01*
G01X1010085Y1823743D02*
X1010304Y1823855D01*
G01X1010851Y1822737D02*
X1011179Y1822849D01*
G01X1049087Y1867150D02*
G03I-18701J0D01*
G01X1016843Y1831874D02*
X1003417D01*
G01Y1829630D02*
X1007748D01*
G01X1003417D02*
X1007748D01*
G01X1003417D02*
Y1901008D01*
G01Y1829630D02*
Y1901008D01*
G01X1038260Y1867150D02*
G03I-7874J0D01*
G01X1038850D02*
G03I-8464J0D01*
G01X1039244D02*
G03I-8858J0D01*
G01X1039835D02*
G03I-9449J0D01*
G01X1040130D02*
G03I-9744J0D01*
G01X1040228D02*
G03I-9842J0D01*
G01D02*
G03I-9842J0D01*
G01X1045543D02*
G03I-15157J0D01*
G01X1046134D02*
G03I-15748J0D01*
G01X1002907Y1826363D02*
X1001997Y1827938D01*
G01X1011997D02*
X1003816D01*
G01D02*
X1002907Y1826363D01*
G01X1012907D02*
X1011997Y1827938D01*
G01X1003417Y1901008D02*
X1057354D01*
G01X1003417D02*
X1057354D01*
G01X1055977Y1933883D02*
G03I-7874J0D01*
G01X1063851D02*
G03I-15748J0D01*
G01X1010110Y2112671D02*
Y2093734D01*
G01X1072198Y-37358D02*
X1072920Y-36708D01*
X1073353Y-35950D01*
X1073497Y-34976D01*
X1073208Y-34002D01*
X1072631Y-33244D01*
X1071621Y-32702D01*
X1070466Y-32594D01*
X1069311Y-32811D01*
X1068589Y-33352D01*
X1068012Y-34110D01*
X1067867Y-34868D01*
X1068012Y-35626D01*
X1068589Y-36600D01*
X1064836Y-36275D01*
Y-33352D01*
G01X1066279Y-28372D02*
X1065414Y-27722D01*
X1064980Y-26965D01*
X1064836Y-26098D01*
X1065125Y-25016D01*
X1065846Y-24258D01*
X1066712Y-24041D01*
X1067579Y-24150D01*
X1068300Y-24583D01*
X1069744Y-26748D01*
X1070754Y-27722D01*
X1072198Y-28372D01*
X1073497Y-28589D01*
Y-24041D01*
G01X1073786Y-17654D02*
X1073641Y-17871D01*
X1073353D01*
X1073208Y-17654D01*
X1073353Y-17437D01*
X1073641D01*
X1073786Y-17654D01*
G01X1072198Y-11375D02*
X1072920Y-10725D01*
X1073353Y-9967D01*
X1073497Y-8993D01*
X1073208Y-8019D01*
X1072631Y-7261D01*
X1071621Y-6719D01*
X1070466Y-6611D01*
X1069311Y-6828D01*
X1068589Y-7369D01*
X1068012Y-8127D01*
X1067867Y-8885D01*
X1068012Y-9643D01*
X1068589Y-10617D01*
X1064836Y-10292D01*
Y-7369D01*
G01Y-332D02*
X1065125Y-1198D01*
X1065846Y-1848D01*
X1066712Y-2281D01*
X1067867Y-2606D01*
X1069167Y-2714D01*
X1070466Y-2606D01*
X1071621Y-2281D01*
X1072487Y-1848D01*
X1073208Y-1198D01*
X1073497Y-332D01*
X1073208Y534D01*
X1072487Y1184D01*
X1071621Y1617D01*
X1070466Y1942D01*
X1069167Y2050D01*
X1067867Y1942D01*
X1066712Y1617D01*
X1065846Y1184D01*
X1065125Y534D01*
X1064836Y-332D01*
G01X1075662Y83489D02*
Y7247D01*
G01Y83489D02*
X1130387D01*
G01X1071725D02*
G03X1075662Y87426I0J3937D01*
G01X1071725Y83489D02*
G03X1075662Y87426I0J3937D01*
G01Y1969316D02*
Y87426D01*
G01Y1969316D02*
Y87426D01*
G01X1063576Y385024D02*
Y152032D01*
G01X1062276Y182028D02*
Y355028D01*
G01X1059276Y342528D02*
Y194528D01*
G01X1057276Y198528D02*
Y243528D01*
G01X1057076D02*
Y293528D01*
G01Y243528D02*
X1059271D01*
G01X1057276Y293528D02*
Y338528D01*
G01X1057076Y293528D02*
X1059271D01*
G01X1057354Y1901008D02*
Y1734079D01*
G01Y1901008D02*
Y1734079D01*
G01X1075662Y1969316D02*
G03X1071725Y1973253I-3937J0D01*
G01X1075662Y1969316D02*
G03X1071725Y1973253I-3937J0D01*
G01X1120419Y-80235D02*
X1121413Y-80046D01*
X1122549Y-79478D01*
X1123260Y-78531D01*
X1123544Y-77205D01*
X1123260Y-75880D01*
X1122407Y-74743D01*
X1121129Y-74175D01*
X1119709D01*
X1118857Y-73797D01*
X1118146Y-72850D01*
X1117862Y-71524D01*
X1118289Y-70199D01*
X1119283Y-69252D01*
X1120419Y-68873D01*
X1121555Y-69252D01*
X1122549Y-70199D01*
X1122976Y-71524D01*
X1122691Y-72850D01*
X1121981Y-73797D01*
X1121129Y-74175D01*
X1119709D01*
X1118431Y-74743D01*
X1117578Y-75880D01*
X1117294Y-77205D01*
X1117578Y-78531D01*
X1118289Y-79478D01*
X1119425Y-80046D01*
X1120419Y-80235D01*
G01X1145196Y-21867D02*
X1146063Y-22589D01*
X1147037Y-23022D01*
X1147903D01*
X1148769Y-22589D01*
X1149419Y-21867D01*
X1149744Y-20857D01*
X1149527Y-19846D01*
X1148986Y-18980D01*
X1148011Y-18403D01*
X1146712Y-18114D01*
X1145954Y-17537D01*
X1145629Y-16526D01*
X1145846Y-15516D01*
X1146387Y-14794D01*
X1147145Y-14361D01*
X1147903D01*
X1148661Y-14650D01*
X1149311Y-15371D01*
G01X1158513Y-15083D02*
X1157863Y-14650D01*
X1157105Y-14361D01*
X1156239D01*
X1155265Y-14794D01*
X1154507Y-15516D01*
X1153966Y-16382D01*
X1153532Y-17825D01*
X1153424Y-19125D01*
X1153641Y-20424D01*
X1153966Y-21290D01*
X1154615Y-22156D01*
X1155373Y-22733D01*
X1156131Y-23022D01*
X1156889D01*
X1157647Y-22733D01*
X1158296Y-22300D01*
X1158838Y-21723D01*
G01X1162085Y-23022D02*
X1164792Y-14361D01*
X1167499Y-23022D01*
G01X1166524Y-19991D02*
X1163060D01*
G01X1171288Y-14361D02*
Y-23022D01*
X1175618D01*
G01X1184279D02*
X1179949D01*
Y-14361D01*
X1184279D01*
G01X1182547Y-18547D02*
X1179949D01*
G01X1130366Y-2091D02*
X1129716Y-1658D01*
X1128958Y-1369D01*
X1128092D01*
X1127118Y-1802D01*
X1126360Y-2524D01*
X1125819Y-3390D01*
X1125385Y-4833D01*
X1125277Y-6133D01*
X1125494Y-7432D01*
X1125819Y-8298D01*
X1126468Y-9164D01*
X1127226Y-9741D01*
X1127984Y-10030D01*
X1128742D01*
X1129500Y-9741D01*
X1130149Y-9308D01*
X1130691Y-8731D01*
G01X1136645Y-10030D02*
X1135995Y-9886D01*
X1135346Y-9308D01*
X1134913Y-8298D01*
X1134696Y-7143D01*
X1134913Y-5988D01*
X1135346Y-4978D01*
X1135995Y-4400D01*
X1136645Y-4256D01*
X1137295Y-4400D01*
X1137944Y-4978D01*
X1138377Y-5988D01*
X1138486Y-7143D01*
X1138377Y-8298D01*
X1137944Y-9308D01*
X1137295Y-9886D01*
X1136645Y-10030D01*
G01X1142058D02*
Y-4256D01*
G01Y-5844D02*
X1142383Y-5122D01*
X1142924Y-4545D01*
X1143682Y-4256D01*
X1144440Y-4545D01*
X1144981Y-5122D01*
X1145306Y-5844D01*
Y-10030D01*
G01Y-5844D02*
X1145631Y-5122D01*
X1146172Y-4545D01*
X1146930Y-4256D01*
X1147688Y-4545D01*
X1148229Y-5122D01*
X1148554Y-5988D01*
Y-10030D01*
G01X1152018Y-12917D02*
Y-4256D01*
G01Y-5555D02*
X1152560Y-4833D01*
X1153101Y-4400D01*
X1153967Y-4256D01*
X1154725Y-4400D01*
X1155483Y-5122D01*
X1155808Y-6133D01*
X1155916Y-7143D01*
X1155808Y-8154D01*
X1155483Y-9164D01*
X1154833Y-9741D01*
X1153967Y-10030D01*
X1153209Y-9886D01*
X1152451Y-9453D01*
X1152018Y-8875D01*
G01X1162628Y-10030D02*
X1161978Y-9886D01*
X1161329Y-9308D01*
X1160896Y-8298D01*
X1160679Y-7143D01*
X1160896Y-5988D01*
X1161329Y-4978D01*
X1161978Y-4400D01*
X1162628Y-4256D01*
X1163278Y-4400D01*
X1163927Y-4978D01*
X1164360Y-5988D01*
X1164469Y-7143D01*
X1164360Y-8298D01*
X1163927Y-9308D01*
X1163278Y-9886D01*
X1162628Y-10030D01*
G01X1169448D02*
Y-4256D01*
G01Y-5700D02*
X1169882Y-4978D01*
X1170531Y-4400D01*
X1171397Y-4256D01*
X1172155Y-4400D01*
X1172805Y-4978D01*
X1173130Y-5988D01*
Y-10030D01*
G01X1178326Y-6133D02*
X1181791D01*
X1181466Y-5122D01*
X1180924Y-4545D01*
X1180167Y-4256D01*
X1179409Y-4400D01*
X1178759Y-4833D01*
X1178326Y-5844D01*
X1178109Y-6710D01*
Y-7576D01*
X1178326Y-8442D01*
X1178867Y-9308D01*
X1179517Y-9886D01*
X1180275Y-10030D01*
X1181033Y-9741D01*
X1181791Y-8875D01*
G01X1186770Y-10030D02*
Y-4256D01*
G01Y-5700D02*
X1187204Y-4978D01*
X1187853Y-4400D01*
X1188719Y-4256D01*
X1189477Y-4400D01*
X1190127Y-4978D01*
X1190452Y-5988D01*
Y-10030D01*
G01X1197272Y-1369D02*
Y-10030D01*
G01X1195756Y-4256D02*
X1198788D01*
G01X1212320Y-8875D02*
X1213187Y-9597D01*
X1214161Y-10030D01*
X1215027D01*
X1215893Y-9597D01*
X1216543Y-8875D01*
X1216868Y-7865D01*
X1216651Y-6854D01*
X1216110Y-5988D01*
X1215135Y-5411D01*
X1213836Y-5122D01*
X1213078Y-4545D01*
X1212753Y-3534D01*
X1212970Y-2524D01*
X1213511Y-1802D01*
X1214269Y-1369D01*
X1215027D01*
X1215785Y-1658D01*
X1216435Y-2379D01*
G01X1223255Y-4256D02*
Y-10030D01*
G01Y-1947D02*
X1223038Y-1802D01*
Y-1513D01*
X1223255Y-1369D01*
X1223472Y-1513D01*
Y-1802D01*
X1223255Y-1947D01*
G01X1233865Y-1369D02*
Y-10030D01*
G01Y-8731D02*
X1233432Y-9453D01*
X1232782Y-9886D01*
X1232024Y-10030D01*
X1231158Y-9741D01*
X1230509Y-9020D01*
X1230075Y-8154D01*
X1229967Y-7143D01*
X1230075Y-6133D01*
X1230509Y-5266D01*
X1231158Y-4545D01*
X1232024Y-4256D01*
X1232782Y-4400D01*
X1233323Y-4689D01*
X1233865Y-5266D01*
G01X1238953Y-6133D02*
X1242418D01*
X1242093Y-5122D01*
X1241551Y-4545D01*
X1240794Y-4256D01*
X1240036Y-4400D01*
X1239386Y-4833D01*
X1238953Y-5844D01*
X1238736Y-6710D01*
Y-7576D01*
X1238953Y-8442D01*
X1239494Y-9308D01*
X1240144Y-9886D01*
X1240902Y-10030D01*
X1241660Y-9741D01*
X1242418Y-8875D01*
G01X1137965Y85654D02*
Y94315D01*
X1136666Y92583D01*
G01Y85654D02*
X1139264D01*
G01X1146626Y94315D02*
X1145760Y94026D01*
X1145110Y93305D01*
X1144677Y92439D01*
X1144352Y91284D01*
X1144244Y89984D01*
X1144352Y88685D01*
X1144677Y87530D01*
X1145110Y86664D01*
X1145760Y85943D01*
X1146626Y85654D01*
X1147492Y85943D01*
X1148142Y86664D01*
X1148575Y87530D01*
X1148900Y88685D01*
X1149008Y89984D01*
X1148900Y91284D01*
X1148575Y92439D01*
X1148142Y93305D01*
X1147492Y94026D01*
X1146626Y94315D01*
G01X1155287Y85365D02*
X1155070Y85510D01*
Y85798D01*
X1155287Y85943D01*
X1155504Y85798D01*
Y85510D01*
X1155287Y85365D01*
G01X1163948Y94315D02*
X1163082Y94026D01*
X1162432Y93305D01*
X1161999Y92439D01*
X1161674Y91284D01*
X1161566Y89984D01*
X1161674Y88685D01*
X1161999Y87530D01*
X1162432Y86664D01*
X1163082Y85943D01*
X1163948Y85654D01*
X1164814Y85943D01*
X1165464Y86664D01*
X1165897Y87530D01*
X1166222Y88685D01*
X1166330Y89984D01*
X1166222Y91284D01*
X1165897Y92439D01*
X1165464Y93305D01*
X1164814Y94026D01*
X1163948Y94315D01*
G01X1172609D02*
X1171743Y94026D01*
X1171093Y93305D01*
X1170660Y92439D01*
X1170335Y91284D01*
X1170227Y89984D01*
X1170335Y88685D01*
X1170660Y87530D01*
X1171093Y86664D01*
X1171743Y85943D01*
X1172609Y85654D01*
X1173475Y85943D01*
X1174125Y86664D01*
X1174558Y87530D01*
X1174883Y88685D01*
X1174991Y89984D01*
X1174883Y91284D01*
X1174558Y92439D01*
X1174125Y93305D01*
X1173475Y94026D01*
X1172609Y94315D01*
G01X1120419Y2097521D02*
X1121413Y2097710D01*
X1122549Y2098278D01*
X1123260Y2099225D01*
X1123544Y2100551D01*
X1123260Y2101876D01*
X1122407Y2103013D01*
X1121129Y2103581D01*
X1119709D01*
X1118857Y2103959D01*
X1118146Y2104906D01*
X1117862Y2106232D01*
X1118289Y2107557D01*
X1119283Y2108504D01*
X1120419Y2108883D01*
X1121555Y2108504D01*
X1122549Y2107557D01*
X1122976Y2106232D01*
X1122691Y2104906D01*
X1121981Y2103959D01*
X1121129Y2103581D01*
X1119709D01*
X1118431Y2103013D01*
X1117578Y2101876D01*
X1117294Y2100551D01*
X1117578Y2099225D01*
X1118289Y2098278D01*
X1119425Y2097710D01*
X1120419Y2097521D01*
G01X1194242Y-23022D02*
Y-14361D01*
X1192943Y-16093D01*
G01Y-23022D02*
X1195541D01*
G01X1202903Y-23311D02*
X1202686Y-23166D01*
Y-22878D01*
X1202903Y-22733D01*
X1203120Y-22878D01*
Y-23166D01*
X1202903Y-23311D01*
G01X1211564Y-14361D02*
X1210698Y-14650D01*
X1210048Y-15371D01*
X1209615Y-16237D01*
X1209290Y-17392D01*
X1209182Y-18692D01*
X1209290Y-19991D01*
X1209615Y-21146D01*
X1210048Y-22012D01*
X1210698Y-22733D01*
X1211564Y-23022D01*
X1212430Y-22733D01*
X1213080Y-22012D01*
X1213513Y-21146D01*
X1213838Y-19991D01*
X1213946Y-18692D01*
X1213838Y-17392D01*
X1213513Y-16237D01*
X1213080Y-15371D01*
X1212430Y-14650D01*
X1211564Y-14361D01*
G01X1220225D02*
X1219359Y-14650D01*
X1218709Y-15371D01*
X1218276Y-16237D01*
X1217951Y-17392D01*
X1217843Y-18692D01*
X1217951Y-19991D01*
X1218276Y-21146D01*
X1218709Y-22012D01*
X1219359Y-22733D01*
X1220225Y-23022D01*
X1221091Y-22733D01*
X1221741Y-22012D01*
X1222174Y-21146D01*
X1222499Y-19991D01*
X1222607Y-18692D01*
X1222499Y-17392D01*
X1222174Y-16237D01*
X1221741Y-15371D01*
X1221091Y-14650D01*
X1220225Y-14361D01*
G01X1228886D02*
X1228020Y-14650D01*
X1227370Y-15371D01*
X1226937Y-16237D01*
X1226612Y-17392D01*
X1226504Y-18692D01*
X1226612Y-19991D01*
X1226937Y-21146D01*
X1227370Y-22012D01*
X1228020Y-22733D01*
X1228886Y-23022D01*
X1229752Y-22733D01*
X1230402Y-22012D01*
X1230835Y-21146D01*
X1231160Y-19991D01*
X1231268Y-18692D01*
X1231160Y-17392D01*
X1230835Y-16237D01*
X1230402Y-15371D01*
X1229752Y-14650D01*
X1228886Y-14361D01*
G01X1229780Y-65085D02*
Y-84022D01*
G01Y2112671D02*
Y2093734D01*
G01X1337673Y-78910D02*
X1338668Y-79856D01*
X1339804Y-80235D01*
X1340940Y-79856D01*
X1341934Y-78720D01*
X1342645Y-77016D01*
X1342929Y-75311D01*
Y-73229D01*
X1342645Y-71524D01*
X1341934Y-70009D01*
X1341082Y-69252D01*
X1340088Y-68873D01*
X1338952Y-69252D01*
X1338100Y-70009D01*
X1337531Y-71145D01*
X1337247Y-72661D01*
X1337531Y-73986D01*
X1338242Y-75311D01*
X1339094Y-76069D01*
X1340088Y-76258D01*
X1341224Y-75880D01*
X1342076Y-74933D01*
X1342929Y-73229D01*
G01X1337673Y2098846D02*
X1338668Y2097900D01*
X1339804Y2097521D01*
X1340940Y2097900D01*
X1341934Y2099036D01*
X1342645Y2100740D01*
X1342929Y2102445D01*
Y2104527D01*
X1342645Y2106232D01*
X1341934Y2107747D01*
X1341082Y2108504D01*
X1340088Y2108883D01*
X1338952Y2108504D01*
X1338100Y2107747D01*
X1337531Y2106611D01*
X1337247Y2105095D01*
X1337531Y2103770D01*
X1338242Y2102445D01*
X1339094Y2101687D01*
X1340088Y2101498D01*
X1341224Y2101876D01*
X1342076Y2102823D01*
X1342929Y2104527D01*
G01X1449449Y-65085D02*
Y-84022D01*
G01X1452019Y61474D02*
G03X1455956Y57537I3937J0D01*
G01X1452019Y61474D02*
G03X1455956Y57537I3937J0D01*
G01X1452019Y61474D02*
Y2022104D01*
G01Y61474D02*
Y2022104D01*
G01X1516980Y57537D02*
X1455956D01*
G01X1516980D02*
X1455956D01*
G01X1485484Y1396120D02*
G03I-15748J0D01*
G01X1455956Y2026041D02*
G03X1452019Y2022104I0J-3937D01*
G01X1455956Y2026041D02*
G03X1452019Y2022104I0J-3937D01*
G01X1455956Y2026041D02*
X1516980D01*
G01X1455956D02*
X1516980D01*
G01X1449449Y2112671D02*
Y2093734D01*
G01X1509176Y-5878D02*
X1510043Y-6600D01*
X1511017Y-7033D01*
X1511883D01*
X1512749Y-6600D01*
X1513399Y-5878D01*
X1513724Y-4868D01*
X1513507Y-3857D01*
X1512966Y-2991D01*
X1511991Y-2414D01*
X1510692Y-2125D01*
X1509934Y-1548D01*
X1509609Y-537D01*
X1509826Y473D01*
X1510367Y1195D01*
X1511125Y1628D01*
X1511883D01*
X1512641Y1339D01*
X1513291Y618D01*
G01X1522493Y906D02*
X1521843Y1339D01*
X1521085Y1628D01*
X1520219D01*
X1519245Y1195D01*
X1518487Y473D01*
X1517946Y-393D01*
X1517512Y-1836D01*
X1517404Y-3136D01*
X1517621Y-4435D01*
X1517946Y-5301D01*
X1518595Y-6167D01*
X1519353Y-6744D01*
X1520111Y-7033D01*
X1520869D01*
X1521627Y-6744D01*
X1522276Y-6311D01*
X1522818Y-5734D01*
G01X1526065Y-7033D02*
X1528772Y1628D01*
X1531479Y-7033D01*
G01X1530504Y-4002D02*
X1527040D01*
G01X1535268Y1628D02*
Y-7033D01*
X1539598D01*
G01X1548259D02*
X1543929D01*
Y1628D01*
X1548259D01*
G01X1546527Y-2558D02*
X1543929D01*
G01X1502681Y7114D02*
X1503548Y6392D01*
X1504522Y5959D01*
X1505388D01*
X1506254Y6392D01*
X1506904Y7114D01*
X1507229Y8124D01*
X1507012Y9135D01*
X1506471Y10001D01*
X1505496Y10578D01*
X1504197Y10867D01*
X1503439Y11444D01*
X1503114Y12455D01*
X1503331Y13465D01*
X1503872Y14187D01*
X1504630Y14620D01*
X1505388D01*
X1506146Y14331D01*
X1506796Y13610D01*
G01X1513616Y5959D02*
X1512966Y6103D01*
X1512317Y6681D01*
X1511884Y7691D01*
X1511667Y8846D01*
X1511884Y10001D01*
X1512317Y11011D01*
X1512966Y11589D01*
X1513616Y11733D01*
X1514266Y11589D01*
X1514915Y11011D01*
X1515348Y10001D01*
X1515457Y8846D01*
X1515348Y7691D01*
X1514915Y6681D01*
X1514266Y6103D01*
X1513616Y5959D01*
G01X1522277D02*
Y14620D01*
G01X1532887D02*
Y5959D01*
G01Y7258D02*
X1532454Y6536D01*
X1531804Y6103D01*
X1531046Y5959D01*
X1530180Y6248D01*
X1529531Y6969D01*
X1529097Y7835D01*
X1528989Y8846D01*
X1529097Y9856D01*
X1529531Y10723D01*
X1530180Y11444D01*
X1531046Y11733D01*
X1531804Y11589D01*
X1532345Y11300D01*
X1532887Y10723D01*
G01X1537975Y9856D02*
X1541440D01*
X1541115Y10867D01*
X1540573Y11444D01*
X1539816Y11733D01*
X1539058Y11589D01*
X1538408Y11156D01*
X1537975Y10145D01*
X1537758Y9279D01*
Y8413D01*
X1537975Y7547D01*
X1538516Y6681D01*
X1539166Y6103D01*
X1539924Y5959D01*
X1540682Y6248D01*
X1541440Y7114D01*
G01X1546744Y5959D02*
Y11733D01*
G01Y10578D02*
X1547286Y11156D01*
X1547827Y11589D01*
X1548585Y11733D01*
X1549126Y11589D01*
X1549776Y11156D01*
G01X1563308Y7114D02*
X1564175Y6392D01*
X1565149Y5959D01*
X1566015D01*
X1566881Y6392D01*
X1567531Y7114D01*
X1567856Y8124D01*
X1567639Y9135D01*
X1567098Y10001D01*
X1566123Y10578D01*
X1564824Y10867D01*
X1564066Y11444D01*
X1563741Y12455D01*
X1563958Y13465D01*
X1564499Y14187D01*
X1565257Y14620D01*
X1566015D01*
X1566773Y14331D01*
X1567423Y13610D01*
G01X1574243Y11733D02*
Y5959D01*
G01Y14042D02*
X1574026Y14187D01*
Y14476D01*
X1574243Y14620D01*
X1574460Y14476D01*
Y14187D01*
X1574243Y14042D01*
G01X1584853Y14620D02*
Y5959D01*
G01Y7258D02*
X1584420Y6536D01*
X1583770Y6103D01*
X1583012Y5959D01*
X1582146Y6248D01*
X1581497Y6969D01*
X1581063Y7835D01*
X1580955Y8846D01*
X1581063Y9856D01*
X1581497Y10723D01*
X1582146Y11444D01*
X1583012Y11733D01*
X1583770Y11589D01*
X1584311Y11300D01*
X1584853Y10723D01*
G01X1589941Y9856D02*
X1593406D01*
X1593081Y10867D01*
X1592539Y11444D01*
X1591782Y11733D01*
X1591024Y11589D01*
X1590374Y11156D01*
X1589941Y10145D01*
X1589724Y9279D01*
Y8413D01*
X1589941Y7547D01*
X1590482Y6681D01*
X1591132Y6103D01*
X1591890Y5959D01*
X1592648Y6248D01*
X1593406Y7114D01*
G01X1489027Y82341D02*
G03I-7087J0D01*
G01X1497688D02*
G03I-15748J0D01*
G01X1504972Y125648D02*
G03I-5709J0D01*
G01X1489027Y168955D02*
G03I-7087J0D01*
G01X1497688D02*
G03I-15748J0D01*
G01X1487452Y215018D02*
G03I-7874J0D01*
G01X1495326D02*
G03I-15748J0D01*
G01X1489027Y515569D02*
G03I-7087J0D01*
G01X1497688D02*
G03I-15748J0D01*
G01X1504972Y558876D02*
G03I-5709J0D01*
G01X1489027Y602183D02*
G03I-7087J0D01*
G01X1497688D02*
G03I-15748J0D01*
G01X1486468Y687459D02*
G03I-6890J0D01*
G01X1495326D02*
G03I-15748J0D01*
G01X1489027Y775411D02*
G03I-7087J0D01*
G01X1497688D02*
G03I-15748J0D01*
G01X1504972Y818719D02*
G03I-5709J0D01*
G01X1497688Y862026D02*
G03I-15748J0D01*
G01X1489027D02*
G03I-7087J0D01*
G01X1497688Y1221553D02*
G03I-15748J0D01*
G01X1504972Y1264860D02*
G03I-5709J0D01*
G01X1489027Y1221553D02*
G03I-7087J0D01*
G01Y1308167D02*
G03I-7087J0D01*
G01X1497688D02*
G03I-15748J0D01*
G01X1476625Y1396120D02*
G03I-6889J0D01*
G01X1497688Y1481396D02*
G03I-15748J0D01*
G01X1504972Y1524703D02*
G03I-5709J0D01*
G01X1489027Y1481396D02*
G03I-7087J0D01*
G01Y1568010D02*
G03I-7087J0D01*
G01X1497688D02*
G03I-15748J0D01*
G01X1486468Y1868561D02*
G03I-6890J0D01*
G01X1495326D02*
G03I-15748J0D01*
G01X1489027Y1914624D02*
G03I-7087J0D01*
G01X1497688D02*
G03I-15748J0D01*
G01X1504972Y1957931D02*
G03I-5709J0D01*
G01X1489027Y2001238D02*
G03I-7087J0D01*
G01X1497688D02*
G03I-15748J0D01*
G01X1557106Y-80235D02*
Y-68873D01*
X1555402Y-71145D01*
G01Y-80235D02*
X1558810D01*
G01X1568469Y-68873D02*
X1567333Y-69252D01*
X1566481Y-70199D01*
X1565912Y-71335D01*
X1565486Y-72850D01*
X1565344Y-74554D01*
X1565486Y-76258D01*
X1565912Y-77773D01*
X1566481Y-78910D01*
X1567333Y-79856D01*
X1568469Y-80235D01*
X1569605Y-79856D01*
X1570457Y-78910D01*
X1571026Y-77773D01*
X1571452Y-76258D01*
X1571594Y-74554D01*
X1571452Y-72850D01*
X1571026Y-71335D01*
X1570457Y-70199D01*
X1569605Y-69252D01*
X1568469Y-68873D01*
G01X1513280Y-65085D02*
X1903043D01*
G01X1558221Y-7033D02*
Y1628D01*
X1556922Y-104D01*
G01Y-7033D02*
X1559520D01*
G01X1566882Y-7322D02*
X1566665Y-7177D01*
Y-6889D01*
X1566882Y-6744D01*
X1567099Y-6889D01*
Y-7177D01*
X1566882Y-7322D01*
G01X1575543Y1628D02*
X1574677Y1339D01*
X1574027Y618D01*
X1573594Y-248D01*
X1573269Y-1403D01*
X1573161Y-2703D01*
X1573269Y-4002D01*
X1573594Y-5157D01*
X1574027Y-6023D01*
X1574677Y-6744D01*
X1575543Y-7033D01*
X1576409Y-6744D01*
X1577059Y-6023D01*
X1577492Y-5157D01*
X1577817Y-4002D01*
X1577925Y-2703D01*
X1577817Y-1403D01*
X1577492Y-248D01*
X1577059Y618D01*
X1576409Y1339D01*
X1575543Y1628D01*
G01X1584204D02*
X1583338Y1339D01*
X1582688Y618D01*
X1582255Y-248D01*
X1581930Y-1403D01*
X1581822Y-2703D01*
X1581930Y-4002D01*
X1582255Y-5157D01*
X1582688Y-6023D01*
X1583338Y-6744D01*
X1584204Y-7033D01*
X1585070Y-6744D01*
X1585720Y-6023D01*
X1586153Y-5157D01*
X1586478Y-4002D01*
X1586586Y-2703D01*
X1586478Y-1403D01*
X1586153Y-248D01*
X1585720Y618D01*
X1585070Y1339D01*
X1584204Y1628D01*
G01X1592865D02*
X1591999Y1339D01*
X1591349Y618D01*
X1590916Y-248D01*
X1590591Y-1403D01*
X1590483Y-2703D01*
X1590591Y-4002D01*
X1590916Y-5157D01*
X1591349Y-6023D01*
X1591999Y-6744D01*
X1592865Y-7033D01*
X1593731Y-6744D01*
X1594381Y-6023D01*
X1594814Y-5157D01*
X1595139Y-4002D01*
X1595247Y-2703D01*
X1595139Y-1403D01*
X1594814Y-248D01*
X1594381Y618D01*
X1593731Y1339D01*
X1592865Y1628D01*
G01X1516980Y57537D02*
G03X1520917Y61474I0J3937D01*
G01X1516980Y57537D02*
G03X1520917Y61474I0J3937D01*
G01Y92971D02*
Y61474D01*
G01Y92971D02*
Y61474D01*
G01X1524854Y96908D02*
G03X1520917Y92971I0J-3937D01*
G01X1524854Y96908D02*
G03X1520917Y92971I0J-3937D01*
G01X1654775Y96908D02*
X1524854D01*
G01X1654775D02*
X1524854D01*
G01X1559868Y1196107D02*
X1558193Y1196869D01*
G01X1579972Y1209932D02*
X1553167Y1208996D01*
G01X1559030Y1205100D02*
X1579972Y1205831D01*
G01X1553167Y1204895D02*
X1555680Y1204983D01*
G01X1579972Y1196809D02*
X1559868Y1196107D01*
G01Y1192006D02*
X1579972Y1192708D01*
G01Y1183686D02*
X1559868Y1182984D01*
G01X1558193Y1196869D02*
X1557355Y1197660D01*
G01X1554004Y1195082D02*
X1556517Y1192709D01*
G01X1558193Y1183745D02*
X1557355Y1184536D01*
G01X1554004Y1181959D02*
X1555680Y1180377D01*
G01X1559868Y1182984D02*
X1558193Y1183745D01*
G01X1555680Y1180377D02*
X1559868Y1178883D01*
G01D02*
X1579972Y1179585D01*
G01X1553167Y1197513D02*
X1554004Y1195082D01*
G01X1553167Y1184390D02*
X1554004Y1181959D01*
G01X1557355Y1197660D02*
X1556517Y1199271D01*
G01X1557355Y1184536D02*
X1556517Y1186148D01*
G01X1554004Y1190161D02*
X1553167Y1187671D01*
G01X1556517Y1200911D02*
X1557355Y1203401D01*
G01X1554004Y1203284D02*
X1553167Y1200794D01*
G01X1556517Y1199271D02*
Y1200911D01*
G01Y1186148D02*
Y1188608D01*
G01X1553167Y1187671D02*
Y1184390D01*
G01Y1200794D02*
Y1197513D01*
G01Y1208996D02*
Y1204895D01*
G01X1557355Y1190278D02*
X1558193Y1191127D01*
G01X1556517Y1192709D02*
X1554004Y1190161D01*
G01X1557355Y1203401D02*
X1559030Y1205100D01*
G01X1555680Y1204983D02*
X1554004Y1203284D01*
G01X1556517Y1188608D02*
X1557355Y1190278D01*
G01X1558193Y1191127D02*
X1559868Y1192006D01*
G01X1556517Y1252585D02*
X1552329Y1253259D01*
G01X1557355Y1256715D02*
X1552329Y1257360D01*
G01X1563219Y1256920D02*
X1557355Y1256715D01*
G01X1564056Y1252848D02*
X1556517Y1252585D01*
G01X1568245Y1257915D02*
X1563219Y1256920D01*
G01X1546465Y1255514D02*
X1543952Y1257887D01*
G01X1558193Y1233778D02*
X1557355Y1234569D01*
G01X1552329Y1257360D02*
X1547303Y1260465D01*
G01X1549816Y1253991D02*
X1546465Y1255514D01*
G01X1559868Y1233017D02*
X1558193Y1233778D01*
G01X1559868Y1219893D02*
X1558193Y1220655D01*
G01X1555680Y1217286D02*
X1559868Y1215792D01*
G01X1552329Y1253259D02*
X1549816Y1253991D01*
G01X1579972Y1246842D02*
X1553167Y1245906D01*
G01X1559030Y1242010D02*
X1579972Y1242741D01*
G01X1553167Y1241805D02*
X1555680Y1241893D01*
G01X1579972Y1233719D02*
X1559868Y1233017D01*
G01Y1228915D02*
X1579972Y1229618D01*
G01Y1220595D02*
X1559868Y1219893D01*
G01Y1215792D02*
X1579972Y1216494D01*
G01X1557355Y1234569D02*
X1556517Y1236180D01*
G01X1557355Y1221446D02*
X1556517Y1223057D01*
G01X1543952Y1257887D02*
X1541439Y1261901D01*
G01X1547303Y1260465D02*
X1545628Y1262867D01*
G01X1554004Y1231992D02*
X1556517Y1229619D01*
G01X1558193Y1220655D02*
X1557355Y1221446D01*
G01X1554004Y1218868D02*
X1555680Y1217286D01*
G01X1541439Y1261901D02*
X1540602Y1266793D01*
G01X1545628Y1262867D02*
X1544790Y1266939D01*
G01X1553167Y1234423D02*
X1554004Y1231992D01*
G01X1553167Y1221300D02*
X1554004Y1218868D01*
G01X1556517Y1236180D02*
Y1237821D01*
G01Y1223057D02*
Y1225518D01*
G01X1553167Y1224580D02*
Y1221300D01*
G01Y1237704D02*
Y1234423D01*
G01Y1245906D02*
Y1241805D01*
G01X1556517Y1225518D02*
X1557355Y1227187D01*
G01X1554004Y1227070D02*
X1553167Y1224580D01*
G01X1556517Y1237821D02*
X1557355Y1240311D01*
G01X1554004Y1240194D02*
X1553167Y1237704D01*
G01X1558193Y1228037D02*
X1559868Y1228915D01*
G01X1557355Y1227187D02*
X1558193Y1228037D01*
G01X1556517Y1229619D02*
X1554004Y1227070D01*
G01X1557355Y1240311D02*
X1559030Y1242010D01*
G01X1555680Y1241893D02*
X1554004Y1240194D01*
G01X1563219Y1278245D02*
X1568245Y1277600D01*
G01X1547303Y1312138D02*
X1563219Y1312694D01*
G01X1540602Y1306983D02*
X1563219Y1307773D01*
G01Y1299571D02*
X1568245Y1299746D01*
G01X1556517Y1282112D02*
X1564056Y1282375D01*
G01X1557355Y1278040D02*
X1563219Y1278245D01*
G01X1552329Y1277045D02*
X1557355Y1278040D01*
G01X1552329Y1281146D02*
X1556517Y1282112D01*
G01X1544790Y1266939D02*
X1545628Y1271069D01*
G01X1540602Y1266793D02*
X1541439Y1271743D01*
G01X1563219Y1312694D02*
Y1326637D01*
G01Y1307773D02*
Y1299571D01*
G01X1540602Y1311904D02*
Y1306983D01*
G01X1543952Y1275932D02*
X1546465Y1278480D01*
G01X1545628Y1271069D02*
X1547303Y1273588D01*
G01X1541439Y1271743D02*
X1543952Y1275932D01*
G01X1549816Y1280238D02*
X1552329Y1281146D01*
G01X1546465Y1278480D02*
X1549816Y1280238D01*
G01X1547303Y1273588D02*
X1552329Y1277045D01*
G01X1563219Y1332379D02*
X1540602Y1311904D01*
G01X1563219Y1326637D02*
X1547303Y1312138D01*
G01X1540602Y1361937D02*
X1579972Y1363312D01*
G01X1568245Y1332554D02*
X1563219Y1332379D01*
G01X1551491Y1340172D02*
X1554004Y1338619D01*
G01X1559868Y1350307D02*
X1565732Y1339028D01*
G01X1568245Y1340757D02*
X1559868Y1356048D01*
G01X1540602Y1366858D02*
Y1361937D01*
G01X1559868Y1356048D02*
X1551491Y1340172D01*
G01X1554004Y1338619D02*
X1559868Y1350307D01*
G01X1579972Y1396120D02*
X1540602Y1394745D01*
G01X1561543Y1390555D02*
X1579972Y1391199D01*
G01X1540602Y1389824D02*
X1556517Y1390380D01*
G01Y1367414D02*
X1540602Y1366858D01*
G01X1579972Y1368233D02*
X1561543Y1367589D01*
G01D02*
Y1390555D01*
G01X1556517Y1390380D02*
Y1367414D01*
G01X1540602Y1394745D02*
Y1389824D01*
G01X1558318Y1805372D02*
G03I-9842J0D01*
G01X1567177D02*
G03I-18701J0D01*
G01X1558318Y1880569D02*
G03I-9842J0D01*
G01X1567177D02*
G03I-18701J0D01*
G01X1520917Y1990608D02*
G03X1524854Y1986671I3937J0D01*
G01X1520917Y2022104D02*
G03X1516980Y2026041I-3937J0D01*
G01X1520917Y1990608D02*
G03X1524854Y1986671I3937J0D01*
G01X1520917Y2022104D02*
G03X1516980Y2026041I-3937J0D01*
G01X1524854Y1986671D02*
X1654775D01*
G01X1524854D02*
X1654775D01*
G01X1520917Y2022104D02*
Y1990608D01*
G01Y2022104D02*
Y1990608D01*
G01X1557106Y2097521D02*
Y2108883D01*
X1555402Y2106611D01*
G01Y2097521D02*
X1558810D01*
G01X1568469Y2108883D02*
X1567333Y2108504D01*
X1566481Y2107557D01*
X1565912Y2106421D01*
X1565486Y2104906D01*
X1565344Y2103202D01*
X1565486Y2101498D01*
X1565912Y2099983D01*
X1566481Y2098846D01*
X1567333Y2097900D01*
X1568469Y2097521D01*
X1569605Y2097900D01*
X1570457Y2098846D01*
X1571026Y2099983D01*
X1571452Y2101498D01*
X1571594Y2103202D01*
X1571452Y2104906D01*
X1571026Y2106421D01*
X1570457Y2107557D01*
X1569605Y2108504D01*
X1568469Y2108883D01*
G01X1579972Y1205831D02*
Y1209932D01*
G01Y1192708D02*
Y1196809D01*
G01Y1179585D02*
Y1183686D01*
G01X1568245Y1253814D02*
X1564056Y1252848D01*
G01X1579972Y1242741D02*
Y1246842D01*
G01Y1229618D02*
Y1233719D01*
G01Y1216494D02*
Y1220595D01*
G01Y1268167D02*
X1579134Y1263217D01*
G01X1574946Y1263891D02*
X1573271Y1261372D01*
G01X1579134Y1263217D02*
X1576621Y1259028D01*
G01X1574108Y1256480D02*
X1570758Y1254722D01*
G01X1573271Y1261372D02*
X1568245Y1257915D01*
G01X1576621Y1259028D02*
X1574108Y1256480D01*
G01X1570758Y1254722D02*
X1568245Y1253814D01*
G01Y1277600D02*
X1573271Y1274495D01*
G01X1570758Y1280969D02*
X1574108Y1279446D01*
G01X1568245Y1281701D02*
X1570758Y1280969D01*
G01X1564056Y1282375D02*
X1568245Y1281701D01*
G01X1579972Y1313279D02*
X1568245Y1312869D01*
G01Y1307948D02*
X1579972Y1308358D01*
G01Y1293594D02*
X1575784Y1293448D01*
G01Y1289347D02*
X1579972Y1289493D01*
G01X1576621Y1277073D02*
X1579134Y1273059D01*
G01X1573271Y1274495D02*
X1574946Y1272093D01*
G01X1574108Y1279446D02*
X1576621Y1277073D01*
G01X1579134Y1273059D02*
X1579972Y1268167D01*
G01X1574946Y1272093D02*
X1575784Y1268021D01*
G01X1579972Y1308358D02*
Y1313279D01*
G01Y1289493D02*
Y1293594D01*
G01X1575784Y1293448D02*
Y1289347D01*
G01X1568245Y1312869D02*
Y1332554D01*
G01Y1299746D02*
Y1307948D01*
G01X1575784Y1268021D02*
X1574946Y1263891D01*
G01X1579972Y1363312D02*
Y1368233D01*
G01X1565732Y1339028D02*
X1568245Y1340757D01*
G01X1649657Y1386278D02*
G03I-18701J0D01*
G01X1579972Y1391199D02*
Y1396120D01*
G01X1623279Y1805372D02*
G03I-9843J0D01*
G01X1632137D02*
G03I-18701J0D01*
G01X1623279Y1880569D02*
G03I-9843J0D01*
G01X1632137D02*
G03I-18701J0D01*
G01X1654775Y96908D02*
G03X1658712Y100845I0J3937D01*
G01X1654775Y96908D02*
G03X1658712Y100845I0J3937D01*
G01X1638043Y136278D02*
G03I-6890J0D01*
G01X1646901D02*
G03I-15748J0D01*
G01X1658712Y1982734D02*
Y100845D01*
G01Y1982734D02*
Y100845D01*
G01X1638043Y628404D02*
G03I-6890J0D01*
G01X1646901D02*
G03I-15748J0D01*
G01X1638043Y1218955D02*
G03I-6890J0D01*
G01X1646901D02*
G03I-15748J0D01*
G01X1640799Y1386278D02*
G03I-9843J0D01*
G01X1639027Y1947301D02*
G03I-7874J0D01*
G01X1646901D02*
G03I-15748J0D01*
G01X1658712Y1982734D02*
G03X1654775Y1986671I-3937J0D01*
G01X1658712Y1982734D02*
G03X1654775Y1986671I-3937J0D01*
G01X1669118Y-65085D02*
Y-84022D01*
G01Y2112671D02*
Y2093734D01*
G01X1714894D02*
X2222768D01*
G01X1747369Y18968D02*
Y-41200D01*
G01D02*
X2499470D01*
G01X1774908Y46365D02*
X1773408Y47365D01*
X1771658Y48032D01*
X1769658D01*
X1767408Y47032D01*
X1765658Y45365D01*
X1764408Y43365D01*
X1763408Y40032D01*
X1763158Y37032D01*
X1763658Y34032D01*
X1764408Y32032D01*
X1765908Y30032D01*
X1767658Y28699D01*
X1769408Y28032D01*
X1771158D01*
X1772908Y28699D01*
X1774408Y29698D01*
X1775658Y31031D01*
G01X1785908Y28032D02*
Y41365D01*
G01Y38699D02*
X1787158Y40032D01*
X1788408Y41032D01*
X1790158Y41365D01*
X1791408Y41032D01*
X1792908Y40032D01*
G01X1805658Y37032D02*
X1813658D01*
X1812908Y39365D01*
X1811658Y40698D01*
X1809908Y41365D01*
X1808158Y41032D01*
X1806658Y40032D01*
X1805658Y37698D01*
X1805158Y35698D01*
Y33699D01*
X1805658Y31698D01*
X1806908Y29698D01*
X1808408Y28365D01*
X1810158Y28032D01*
X1811908Y28699D01*
X1813658Y30698D01*
G01X1833908Y28032D02*
Y41365D01*
G01Y39032D02*
X1832908Y40365D01*
X1831408Y41032D01*
X1829658Y41365D01*
X1827908Y40698D01*
X1826408Y39365D01*
X1825408Y37365D01*
X1824908Y34698D01*
X1825408Y32032D01*
X1826408Y30032D01*
X1827908Y28699D01*
X1829658Y28032D01*
X1831408Y28365D01*
X1832908Y29365D01*
X1833908Y30698D01*
G01X1849408Y48032D02*
Y28032D01*
G01X1845908Y41365D02*
X1852908D01*
G01X1865658Y37032D02*
X1873658D01*
X1872908Y39365D01*
X1871658Y40698D01*
X1869908Y41365D01*
X1868158Y41032D01*
X1866658Y40032D01*
X1865658Y37698D01*
X1865158Y35698D01*
Y33699D01*
X1865658Y31698D01*
X1866908Y29698D01*
X1868408Y28365D01*
X1870158Y28032D01*
X1871908Y28699D01*
X1873658Y30698D01*
G01X1893908Y48032D02*
Y28032D01*
G01Y31031D02*
X1892908Y29365D01*
X1891408Y28365D01*
X1889658Y28032D01*
X1887658Y28699D01*
X1886158Y30365D01*
X1885158Y32365D01*
X1884908Y34698D01*
X1885158Y37032D01*
X1886158Y39032D01*
X1887658Y40698D01*
X1889658Y41365D01*
X1891408Y41032D01*
X1892658Y40365D01*
X1893908Y39032D01*
G01X1747369Y18968D02*
Y64094D01*
G01X2537075Y18968D02*
X1747369D01*
G01X1760456Y96940D02*
X1766706Y76940D01*
X1772956Y96940D01*
G01X1782956Y85940D02*
X1790956D01*
X1790206Y88273D01*
X1788956Y89606D01*
X1787206Y90273D01*
X1785456Y89940D01*
X1783956Y88940D01*
X1782956Y86606D01*
X1782456Y84606D01*
Y82607D01*
X1782956Y80606D01*
X1784206Y78606D01*
X1785706Y77273D01*
X1787456Y76940D01*
X1789206Y77607D01*
X1790956Y79606D01*
G01X1803206Y76940D02*
Y90273D01*
G01Y87607D02*
X1804456Y88940D01*
X1805706Y89940D01*
X1807456Y90273D01*
X1808706Y89940D01*
X1810206Y88940D01*
G01X1822956Y79273D02*
X1824206Y77940D01*
X1825956Y76940D01*
X1827456D01*
X1828956Y77607D01*
X1829956Y78606D01*
X1830456Y79939D01*
X1830206Y81940D01*
X1829206Y82940D01*
X1824706Y84940D01*
X1823706Y87274D01*
X1824206Y88940D01*
X1825206Y89940D01*
X1826706Y90273D01*
X1828206Y89940D01*
X1829706Y88940D01*
G01X1846706Y90273D02*
Y76940D01*
G01Y95606D02*
X1846206Y95940D01*
Y96607D01*
X1846706Y96940D01*
X1847206Y96607D01*
Y95940D01*
X1846706Y95606D01*
G01X1866706Y76940D02*
X1865206Y77273D01*
X1863706Y78606D01*
X1862706Y80940D01*
X1862206Y83606D01*
X1862706Y86273D01*
X1863706Y88607D01*
X1865206Y89940D01*
X1866706Y90273D01*
X1868206Y89940D01*
X1869706Y88607D01*
X1870706Y86273D01*
X1870956Y83606D01*
X1870706Y80940D01*
X1869706Y78606D01*
X1868206Y77273D01*
X1866706Y76940D01*
G01X1882456D02*
Y90273D01*
G01Y86940D02*
X1883456Y88607D01*
X1884956Y89940D01*
X1886956Y90273D01*
X1888706Y89940D01*
X1890206Y88607D01*
X1890956Y86273D01*
Y76940D01*
G01X1747369Y64094D02*
Y109220D01*
G01Y64094D02*
X2123420D01*
G01X1764408Y120954D02*
Y140954D01*
X1770408D01*
X1772408Y139954D01*
X1773908Y137621D01*
X1774408Y134954D01*
X1773908Y132287D01*
X1772658Y130287D01*
X1770408Y129287D01*
X1764408D01*
G01X1794908Y139287D02*
X1793408Y140287D01*
X1791658Y140954D01*
X1789658D01*
X1787408Y139954D01*
X1785658Y138287D01*
X1784408Y136287D01*
X1783408Y132954D01*
X1783158Y129954D01*
X1783658Y126954D01*
X1784408Y124954D01*
X1785908Y122954D01*
X1787658Y121621D01*
X1789408Y120954D01*
X1791158D01*
X1792908Y121621D01*
X1794408Y122620D01*
X1795658Y123953D01*
G01X1811408Y131621D02*
X1812408Y132621D01*
X1813158Y134287D01*
X1813658Y136621D01*
X1813158Y138621D01*
X1812158Y139954D01*
X1810408Y140954D01*
X1803658D01*
Y120954D01*
X1811908D01*
X1813658Y122287D01*
X1814658Y124287D01*
X1815158Y126621D01*
X1814658Y128954D01*
X1813158Y130954D01*
X1811408Y131621D01*
X1803658D01*
G01X1843658Y120954D02*
Y140954D01*
X1855158Y120954D01*
Y140954D01*
G01X1869408Y120954D02*
X1867908Y121287D01*
X1866408Y122620D01*
X1865408Y124954D01*
X1864908Y127620D01*
X1865408Y130287D01*
X1866408Y132621D01*
X1867908Y133954D01*
X1869408Y134287D01*
X1870908Y133954D01*
X1872408Y132621D01*
X1873408Y130287D01*
X1873658Y127620D01*
X1873408Y124954D01*
X1872408Y122620D01*
X1870908Y121287D01*
X1869408Y120954D01*
G01X1889408Y120287D02*
X1888908Y120621D01*
Y121287D01*
X1889408Y121621D01*
X1889908Y121287D01*
Y120621D01*
X1889408Y120287D01*
G01X1747369Y109220D02*
Y214489D01*
G01Y109220D02*
X2537075D01*
G01X1747369Y154346D02*
X2537075D01*
G01X1747369Y214489D02*
X2537075D01*
G01X1777533Y-80235D02*
Y-68873D01*
X1775829Y-71145D01*
G01Y-80235D02*
X1779237D01*
G01X1788896D02*
Y-68873D01*
X1787192Y-71145D01*
G01Y-80235D02*
X1790600D01*
G01X1772970Y165167D02*
Y192726D01*
X1781926Y169760D01*
X1790883Y192726D01*
Y165167D01*
G01X1809485D02*
X1807419Y165626D01*
X1805352Y167463D01*
X1803973Y170678D01*
X1803285Y174353D01*
X1803973Y178028D01*
X1805352Y181243D01*
X1807419Y183080D01*
X1809485Y183539D01*
X1811552Y183080D01*
X1813619Y181243D01*
X1814997Y178028D01*
X1815342Y174353D01*
X1814997Y170678D01*
X1813619Y167463D01*
X1811552Y165626D01*
X1809485Y165167D01*
G01X1843245Y192726D02*
Y165167D01*
G01Y169300D02*
X1841867Y167004D01*
X1839800Y165626D01*
X1837389Y165167D01*
X1834633Y166085D01*
X1832566Y168382D01*
X1831188Y171138D01*
X1830844Y174353D01*
X1831188Y177568D01*
X1832566Y180325D01*
X1834633Y182621D01*
X1837389Y183539D01*
X1839800Y183080D01*
X1841523Y182161D01*
X1843245Y180325D01*
G01X1859436Y177568D02*
X1870460D01*
X1869426Y180784D01*
X1867704Y182621D01*
X1865293Y183539D01*
X1862881Y183080D01*
X1860814Y181702D01*
X1859436Y178487D01*
X1858747Y175731D01*
Y172975D01*
X1859436Y170219D01*
X1861158Y167463D01*
X1863226Y165626D01*
X1865637Y165167D01*
X1868049Y166085D01*
X1870460Y168841D01*
G01X1892162Y165167D02*
Y192726D01*
G01X1777533Y2097521D02*
Y2108883D01*
X1775829Y2106611D01*
G01Y2097521D02*
X1779237D01*
G01X1788896D02*
Y2108883D01*
X1787192Y2106611D01*
G01Y2097521D02*
X1790600D01*
G01X1828730Y-2912D02*
X1833552Y-30471D01*
X1839064Y-2912D01*
X1844576Y-30471D01*
X1849399Y-2912D01*
G01X1866623Y-12099D02*
Y-30471D01*
G01Y-4750D02*
X1865934Y-4290D01*
Y-3371D01*
X1866623Y-2912D01*
X1867313Y-3371D01*
Y-4290D01*
X1866623Y-4750D01*
G01X1889015Y-27256D02*
X1890737Y-29093D01*
X1893149Y-30471D01*
X1895216D01*
X1897283Y-29553D01*
X1898661Y-28175D01*
X1899350Y-26338D01*
X1899005Y-23581D01*
X1897628Y-22203D01*
X1891426Y-19448D01*
X1890049Y-16232D01*
X1890737Y-13936D01*
X1892116Y-12558D01*
X1894182Y-12099D01*
X1896249Y-12558D01*
X1898316Y-13936D01*
G01X1921741Y-2912D02*
Y-30471D01*
G01X1916919Y-12099D02*
X1926564D01*
G01X1944478Y-30471D02*
Y-12099D01*
G01Y-15773D02*
X1946200Y-13936D01*
X1947923Y-12558D01*
X1950334Y-12099D01*
X1952056Y-12558D01*
X1954123Y-13936D01*
G01X1976859Y-30471D02*
X1974793Y-30012D01*
X1972726Y-28175D01*
X1971347Y-24960D01*
X1970659Y-21285D01*
X1971347Y-17610D01*
X1972726Y-14395D01*
X1974793Y-12558D01*
X1976859Y-12099D01*
X1978926Y-12558D01*
X1980993Y-14395D01*
X1982371Y-17610D01*
X1982716Y-21285D01*
X1982371Y-24960D01*
X1980993Y-28175D01*
X1978926Y-30012D01*
X1976859Y-30471D01*
G01X1998562D02*
Y-12099D01*
G01Y-16692D02*
X1999940Y-14395D01*
X2002007Y-12558D01*
X2004763Y-12099D01*
X2007174Y-12558D01*
X2009241Y-14395D01*
X2010275Y-17610D01*
Y-30471D01*
G01X2067115Y-5209D02*
X2065048Y-3830D01*
X2062637Y-2912D01*
X2059881D01*
X2056780Y-4290D01*
X2054369Y-6587D01*
X2052647Y-9343D01*
X2051268Y-13936D01*
X2050924Y-18070D01*
X2051613Y-22203D01*
X2052647Y-24960D01*
X2054714Y-27716D01*
X2057125Y-29553D01*
X2059536Y-30471D01*
X2061948D01*
X2064359Y-29553D01*
X2066426Y-28175D01*
X2068149Y-26338D01*
G01X2087095Y-30471D02*
X2085029Y-30012D01*
X2082962Y-28175D01*
X2081583Y-24960D01*
X2080895Y-21285D01*
X2081583Y-17610D01*
X2082962Y-14395D01*
X2085029Y-12558D01*
X2087095Y-12099D01*
X2089162Y-12558D01*
X2091229Y-14395D01*
X2092607Y-17610D01*
X2092952Y-21285D01*
X2092607Y-24960D01*
X2091229Y-28175D01*
X2089162Y-30012D01*
X2087095Y-30471D01*
G01X2109832D02*
Y-12099D01*
G01Y-15773D02*
X2111554Y-13936D01*
X2113277Y-12558D01*
X2115688Y-12099D01*
X2117410Y-12558D01*
X2119477Y-13936D01*
G01X2136013Y-39657D02*
Y-12099D01*
G01Y-16232D02*
X2137735Y-13936D01*
X2139457Y-12558D01*
X2142213Y-12099D01*
X2144625Y-12558D01*
X2147036Y-14854D01*
X2148070Y-18070D01*
X2148414Y-21285D01*
X2148070Y-24500D01*
X2147036Y-27716D01*
X2144969Y-29553D01*
X2142213Y-30471D01*
X2139802Y-30012D01*
X2137391Y-28634D01*
X2136013Y-26797D01*
G01X2169772Y-30471D02*
X2167706Y-30012D01*
X2165639Y-28175D01*
X2164260Y-24960D01*
X2163572Y-21285D01*
X2164260Y-17610D01*
X2165639Y-14395D01*
X2167706Y-12558D01*
X2169772Y-12099D01*
X2171839Y-12558D01*
X2173906Y-14395D01*
X2175284Y-17610D01*
X2175629Y-21285D01*
X2175284Y-24960D01*
X2173906Y-28175D01*
X2171839Y-30012D01*
X2169772Y-30471D01*
G01X2192509D02*
Y-12099D01*
G01Y-15773D02*
X2194231Y-13936D01*
X2195954Y-12558D01*
X2198365Y-12099D01*
X2200087Y-12558D01*
X2202154Y-13936D01*
G01X2231091Y-30471D02*
Y-12099D01*
G01Y-15313D02*
X2229713Y-13477D01*
X2227646Y-12558D01*
X2225235Y-12099D01*
X2222824Y-13017D01*
X2220757Y-14854D01*
X2219378Y-17610D01*
X2218690Y-21285D01*
X2219378Y-24960D01*
X2220757Y-27716D01*
X2222824Y-29553D01*
X2225235Y-30471D01*
X2227646Y-30012D01*
X2229713Y-28634D01*
X2231091Y-26797D01*
G01X2252449Y-2912D02*
Y-30471D01*
G01X2247627Y-12099D02*
X2257272D01*
G01X2280008D02*
Y-30471D01*
G01Y-4750D02*
X2279319Y-4290D01*
Y-3371D01*
X2280008Y-2912D01*
X2280698Y-3371D01*
Y-4290D01*
X2280008Y-4750D01*
G01X2307567Y-30471D02*
X2305501Y-30012D01*
X2303434Y-28175D01*
X2302055Y-24960D01*
X2301367Y-21285D01*
X2302055Y-17610D01*
X2303434Y-14395D01*
X2305501Y-12558D01*
X2307567Y-12099D01*
X2309634Y-12558D01*
X2311701Y-14395D01*
X2313079Y-17610D01*
X2313424Y-21285D01*
X2313079Y-24960D01*
X2311701Y-28175D01*
X2309634Y-30012D01*
X2307567Y-30471D01*
G01X2329270D02*
Y-12099D01*
G01Y-16692D02*
X2330648Y-14395D01*
X2332715Y-12558D01*
X2335471Y-12099D01*
X2337882Y-12558D01*
X2339949Y-14395D01*
X2340983Y-17610D01*
Y-30471D01*
G01X1887841Y-65085D02*
Y-84022D01*
G01X1903043Y-65085D02*
X2553477D01*
G01X1888787Y2112671D02*
Y2093734D01*
G01X1966362Y30007D02*
Y50007D01*
G01X1975862D02*
X1966362Y37673D01*
G01X1977362Y30007D02*
X1970612Y43340D01*
G01X1988112Y39007D02*
X1996112D01*
X1995362Y41340D01*
X1994112Y42673D01*
X1992362Y43340D01*
X1990612Y43007D01*
X1989112Y42007D01*
X1988112Y39673D01*
X1987612Y37673D01*
Y35674D01*
X1988112Y33673D01*
X1989362Y31673D01*
X1990862Y30340D01*
X1992612Y30007D01*
X1994362Y30674D01*
X1996112Y32673D01*
G01X2007612Y30007D02*
Y43340D01*
G01Y40007D02*
X2008612Y41674D01*
X2010112Y43007D01*
X2012112Y43340D01*
X2013862Y43007D01*
X2015362Y41674D01*
X2016112Y39340D01*
Y30007D01*
G01X1935394Y18968D02*
Y214489D01*
G01X1977609Y122928D02*
Y142928D01*
X1974609Y138928D01*
G01Y122928D02*
X1980609D01*
G01X1992859Y139595D02*
X1994359Y141594D01*
X1996109Y142595D01*
X1998109Y142928D01*
X2000609Y142261D01*
X2002359Y140595D01*
X2002859Y138595D01*
X2002609Y136594D01*
X2001609Y134928D01*
X1996609Y131595D01*
X1994359Y129261D01*
X1992859Y125927D01*
X1992359Y122928D01*
X2002859D01*
G01X2020609D02*
Y142928D01*
X2011359Y128595D01*
X2023859D01*
G01X2032109Y126928D02*
X2033609Y124594D01*
X2035609Y123261D01*
X2037859Y122928D01*
X2039859Y123261D01*
X2041859Y124928D01*
X2043109Y126928D01*
X2043359Y128928D01*
X2042859Y131261D01*
X2041109Y132928D01*
X2039359Y133595D01*
X2037109D01*
G01X2039359D02*
X2040859Y134595D01*
X2042109Y136261D01*
X2042609Y138261D01*
X2042109Y140261D01*
X2040859Y141928D01*
X2038609Y142928D01*
X2036359Y142595D01*
X2034109Y141261D01*
G01X2052109Y126928D02*
X2053609Y124594D01*
X2055609Y123261D01*
X2057859Y122928D01*
X2059859Y123261D01*
X2061859Y124928D01*
X2063109Y126928D01*
X2063359Y128928D01*
X2062859Y131261D01*
X2061109Y132928D01*
X2059359Y133595D01*
X2057109D01*
G01X2059359D02*
X2060859Y134595D01*
X2062109Y136261D01*
X2062609Y138261D01*
X2062109Y140261D01*
X2060859Y141928D01*
X2058609Y142928D01*
X2056359Y142595D01*
X2054109Y141261D01*
G01X1960320Y168873D02*
Y192495D01*
G01X1971541D02*
X1960320Y177928D01*
G01X1973313Y168873D02*
X1965340Y184621D01*
G01X1983648Y168873D02*
Y192495D01*
X1997231Y168873D01*
Y192495D01*
G01X2014062Y168873D02*
X2011700Y169267D01*
X2009633Y170841D01*
X2007862Y173203D01*
X2006680Y175960D01*
X2006090Y179109D01*
Y182259D01*
X2006680Y185408D01*
X2007862Y188165D01*
X2009633Y190526D01*
X2011700Y192101D01*
X2014062Y192495D01*
X2016425Y192101D01*
X2018492Y190526D01*
X2020263Y188165D01*
X2021445Y185408D01*
X2022035Y182259D01*
Y179109D01*
X2021445Y175960D01*
X2020263Y173203D01*
X2018492Y170841D01*
X2016425Y169267D01*
X2014062Y168873D01*
G01X2031485D02*
X2043886Y192495D01*
G01X2031485D02*
X2043886Y168873D01*
G01X2079321D02*
Y192495D01*
X2090542D01*
G01X2086408Y181078D02*
X2079321D01*
G01X2101172Y168873D02*
X2108554Y192495D01*
X2115937Y168873D01*
G01X2113279Y177140D02*
X2103830D01*
G01X2125386Y168873D02*
Y192495D01*
X2138969Y168873D01*
Y192495D01*
G01X2185920Y190526D02*
X2184148Y191708D01*
X2182081Y192495D01*
X2179719D01*
X2177061Y191313D01*
X2174994Y189345D01*
X2173518Y186983D01*
X2172336Y183046D01*
X2172041Y179503D01*
X2172632Y175960D01*
X2173518Y173597D01*
X2175290Y171235D01*
X2177357Y169660D01*
X2179423Y168873D01*
X2181490D01*
X2183557Y169660D01*
X2185329Y170841D01*
X2186806Y172416D01*
G01X2203046Y168873D02*
X2200684Y169267D01*
X2198617Y170841D01*
X2196846Y173203D01*
X2195664Y175960D01*
X2195074Y179109D01*
Y182259D01*
X2195664Y185408D01*
X2196846Y188165D01*
X2198617Y190526D01*
X2200684Y192101D01*
X2203046Y192495D01*
X2205409Y192101D01*
X2207476Y190526D01*
X2209247Y188165D01*
X2210429Y185408D01*
X2211019Y182259D01*
Y179109D01*
X2210429Y175960D01*
X2209247Y173203D01*
X2207476Y170841D01*
X2205409Y169267D01*
X2203046Y168873D01*
G01X2219878D02*
Y192495D01*
X2233461Y168873D01*
Y192495D01*
G01X2250292D02*
Y168873D01*
G01X2243501Y192495D02*
X2257084D01*
G01X2268010Y168873D02*
Y192495D01*
X2275392D01*
X2277754Y191313D01*
X2279231Y189739D01*
X2279821Y186589D01*
X2279231Y183440D01*
X2277459Y181472D01*
X2275392Y180290D01*
X2268010D01*
G01X2275392D02*
X2279821Y168873D01*
G01X2297538D02*
X2295176Y169267D01*
X2293109Y170841D01*
X2291338Y173203D01*
X2290156Y175960D01*
X2289566Y179109D01*
Y182259D01*
X2290156Y185408D01*
X2291338Y188165D01*
X2293109Y190526D01*
X2295176Y192101D01*
X2297538Y192495D01*
X2299901Y192101D01*
X2301968Y190526D01*
X2303739Y188165D01*
X2304921Y185408D01*
X2305511Y182259D01*
Y179109D01*
X2304921Y175960D01*
X2303739Y173203D01*
X2301968Y170841D01*
X2299901Y169267D01*
X2297538Y168873D01*
G01X2315256Y192495D02*
Y168873D01*
X2327067D01*
G01X2370770Y181472D02*
X2371951Y182652D01*
X2372837Y184621D01*
X2373428Y187377D01*
X2372837Y189739D01*
X2371656Y191313D01*
X2369589Y192495D01*
X2361616D01*
Y168873D01*
X2371361D01*
X2373428Y170447D01*
X2374608Y172810D01*
X2375199Y175566D01*
X2374608Y178321D01*
X2372837Y180684D01*
X2370770Y181472D01*
X2361616D01*
G01X2392030Y168873D02*
X2389668Y169267D01*
X2387601Y170841D01*
X2385830Y173203D01*
X2384648Y175960D01*
X2384058Y179109D01*
Y182259D01*
X2384648Y185408D01*
X2385830Y188165D01*
X2387601Y190526D01*
X2389668Y192101D01*
X2392030Y192495D01*
X2394393Y192101D01*
X2396460Y190526D01*
X2398231Y188165D01*
X2399413Y185408D01*
X2400003Y182259D01*
Y179109D01*
X2399413Y175960D01*
X2398231Y173203D01*
X2396460Y170841D01*
X2394393Y169267D01*
X2392030Y168873D01*
G01X2408271D02*
X2415653Y192495D01*
X2423036Y168873D01*
G01X2420378Y177140D02*
X2410929D01*
G01X2433371Y168873D02*
Y192495D01*
X2440753D01*
X2443115Y191313D01*
X2444592Y189739D01*
X2445182Y186589D01*
X2444592Y183440D01*
X2442820Y181472D01*
X2440753Y180290D01*
X2433371D01*
G01X2440753D02*
X2445182Y168873D01*
G01X2456403D02*
Y192495D01*
X2462309D01*
X2464671Y191313D01*
X2466443Y189739D01*
X2467920Y187377D01*
X2469100Y184621D01*
X2469396Y180684D01*
X2469100Y176747D01*
X2467920Y173991D01*
X2466443Y171628D01*
X2464671Y170054D01*
X2462309Y168873D01*
X2456403D01*
G01X2480617Y176747D02*
X2486522Y192495D01*
X2492428Y176747D01*
G01X2486522Y192495D02*
Y160999D01*
G01X2506602Y192495D02*
X2513688D01*
G01X2510145D02*
Y168873D01*
G01X2506602D02*
X2513688D01*
G01X1995308Y-80235D02*
Y-68873D01*
X1993604Y-71145D01*
G01Y-80235D02*
X1997012D01*
G01X2003972Y-70767D02*
X2004825Y-69631D01*
X2005819Y-69062D01*
X2006955Y-68873D01*
X2008375Y-69252D01*
X2009370Y-70199D01*
X2009654Y-71335D01*
X2009512Y-72471D01*
X2008943Y-73418D01*
X2006103Y-75311D01*
X2004825Y-76637D01*
X2003972Y-78531D01*
X2003688Y-80235D01*
X2009654D01*
G01X1991639Y72046D02*
Y92046D01*
X1988639Y88046D01*
G01Y72046D02*
X1994639D01*
G01X2005139D02*
Y92046D01*
X2011639Y75379D01*
X2018139Y92046D01*
Y72046D01*
G01X1995308Y2097521D02*
Y2108883D01*
X1993604Y2106611D01*
G01Y2097521D02*
X1997012D01*
G01X2003972Y2106989D02*
X2004825Y2108125D01*
X2005819Y2108694D01*
X2006955Y2108883D01*
X2008375Y2108504D01*
X2009370Y2107557D01*
X2009654Y2106421D01*
X2009512Y2105285D01*
X2008943Y2104338D01*
X2006103Y2102445D01*
X2004825Y2101119D01*
X2003972Y2099225D01*
X2003688Y2097521D01*
X2009654D01*
G01X2108457Y-65085D02*
Y-84022D01*
G01X2123420Y64094D02*
X2537075D01*
G01X2108457Y2112671D02*
Y2093734D01*
G01X2177539Y28032D02*
Y48032D01*
X2182539D01*
X2184539Y47032D01*
X2186039Y45699D01*
X2187289Y43699D01*
X2188289Y41365D01*
X2188539Y38032D01*
X2188289Y34698D01*
X2187289Y32365D01*
X2186039Y30365D01*
X2184539Y29032D01*
X2182539Y28032D01*
X2177539D01*
G01X2207539D02*
Y41365D01*
G01Y39032D02*
X2206539Y40365D01*
X2205039Y41032D01*
X2203289Y41365D01*
X2201539Y40698D01*
X2200039Y39365D01*
X2199039Y37365D01*
X2198539Y34698D01*
X2199039Y32032D01*
X2200039Y30032D01*
X2201539Y28699D01*
X2203289Y28032D01*
X2205039Y28365D01*
X2206539Y29365D01*
X2207539Y30698D01*
G01X2223039Y48032D02*
Y28032D01*
G01X2219539Y41365D02*
X2226539D01*
G01X2239289Y37032D02*
X2247289D01*
X2246539Y39365D01*
X2245289Y40698D01*
X2243539Y41365D01*
X2241789Y41032D01*
X2240289Y40032D01*
X2239289Y37698D01*
X2238789Y35698D01*
Y33699D01*
X2239289Y31698D01*
X2240539Y29698D01*
X2242039Y28365D01*
X2243789Y28032D01*
X2245539Y28699D01*
X2247289Y30698D01*
G01X2140465Y96740D02*
Y76740D01*
G01X2134715Y96740D02*
X2146215D01*
G01X2156215Y76740D02*
Y96740D01*
G01Y87074D02*
X2157465Y88740D01*
X2158715Y89740D01*
X2160715Y90073D01*
X2162215Y89740D01*
X2163965Y88407D01*
X2164715Y86406D01*
Y76740D01*
G01X2180465Y90073D02*
Y76740D01*
G01Y95406D02*
X2179965Y95740D01*
Y96407D01*
X2180465Y96740D01*
X2180965Y96407D01*
Y95740D01*
X2180465Y95406D01*
G01X2204465Y88407D02*
X2202715Y89740D01*
X2201215Y90073D01*
X2199215Y89406D01*
X2197715Y88073D01*
X2196715Y85740D01*
X2196465Y83406D01*
X2196715Y81073D01*
X2197715Y79073D01*
X2199215Y77407D01*
X2201215Y76740D01*
X2202965Y77407D01*
X2204465Y78740D01*
G01X2216215Y76740D02*
Y96740D01*
G01X2224215Y90073D02*
X2216215Y82407D01*
G01X2219465Y85407D02*
X2224715Y76740D01*
G01X2236215D02*
Y90073D01*
G01Y86740D02*
X2237215Y88407D01*
X2238715Y89740D01*
X2240715Y90073D01*
X2242465Y89740D01*
X2243965Y88407D01*
X2244715Y86073D01*
Y76740D01*
G01X2256715Y85740D02*
X2264715D01*
X2263965Y88073D01*
X2262715Y89406D01*
X2260965Y90073D01*
X2259215Y89740D01*
X2257715Y88740D01*
X2256715Y86406D01*
X2256215Y84406D01*
Y82407D01*
X2256715Y80406D01*
X2257965Y78406D01*
X2259465Y77073D01*
X2261215Y76740D01*
X2262965Y77407D01*
X2264715Y79406D01*
G01X2276715Y79073D02*
X2277965Y77740D01*
X2279715Y76740D01*
X2281215D01*
X2282715Y77407D01*
X2283715Y78406D01*
X2284215Y79739D01*
X2283965Y81740D01*
X2282965Y82740D01*
X2278465Y84740D01*
X2277465Y87074D01*
X2277965Y88740D01*
X2278965Y89740D01*
X2280465Y90073D01*
X2281965Y89740D01*
X2283465Y88740D01*
G01X2296715Y79073D02*
X2297965Y77740D01*
X2299715Y76740D01*
X2301215D01*
X2302715Y77407D01*
X2303715Y78406D01*
X2304215Y79739D01*
X2303965Y81740D01*
X2302965Y82740D01*
X2298465Y84740D01*
X2297465Y87074D01*
X2297965Y88740D01*
X2298965Y89740D01*
X2300465Y90073D01*
X2301965Y89740D01*
X2303465Y88740D01*
G01X2214978Y-80235D02*
Y-68873D01*
X2213274Y-71145D01*
G01Y-80235D02*
X2216682D01*
G01X2223216Y-77963D02*
X2224068Y-79288D01*
X2225205Y-80046D01*
X2226483Y-80235D01*
X2227619Y-80046D01*
X2228756Y-79099D01*
X2229466Y-77963D01*
X2229608Y-76826D01*
X2229324Y-75501D01*
X2228329Y-74554D01*
X2227335Y-74175D01*
X2226057D01*
G01X2227335D02*
X2228187Y-73607D01*
X2228898Y-72661D01*
X2229182Y-71524D01*
X2228898Y-70388D01*
X2228187Y-69441D01*
X2226909Y-68873D01*
X2225631Y-69062D01*
X2224353Y-69820D01*
G01X2214978Y2097521D02*
Y2108883D01*
X2213274Y2106611D01*
G01Y2097521D02*
X2216682D01*
G01X2223216Y2099793D02*
X2224068Y2098468D01*
X2225205Y2097710D01*
X2226483Y2097521D01*
X2227619Y2097710D01*
X2228756Y2098657D01*
X2229466Y2099793D01*
X2229608Y2100930D01*
X2229324Y2102255D01*
X2228329Y2103202D01*
X2227335Y2103581D01*
X2226057D01*
G01X2227335D02*
X2228187Y2104149D01*
X2228898Y2105095D01*
X2229182Y2106232D01*
X2228898Y2107368D01*
X2228187Y2108315D01*
X2226909Y2108883D01*
X2225631Y2108694D01*
X2224353Y2107936D01*
G01X2222768Y2093734D02*
X2553476D01*
G01X2328126Y-65085D02*
Y-84022D01*
G01Y2112671D02*
Y2093734D01*
G01X2341770Y46674D02*
X2343270Y48673D01*
X2345020Y49674D01*
X2347020Y50007D01*
X2349520Y49340D01*
X2351270Y47674D01*
X2351770Y45674D01*
X2351520Y43673D01*
X2350520Y42007D01*
X2345520Y38674D01*
X2343270Y36340D01*
X2341770Y33006D01*
X2341270Y30007D01*
X2351770D01*
G01X2366520Y50007D02*
X2364520Y49340D01*
X2363020Y47674D01*
X2362020Y45674D01*
X2361270Y43007D01*
X2361020Y40007D01*
X2361270Y37007D01*
X2362020Y34340D01*
X2363020Y32340D01*
X2364520Y30674D01*
X2366520Y30007D01*
X2368520Y30674D01*
X2370020Y32340D01*
X2371020Y34340D01*
X2371770Y37007D01*
X2372020Y40007D01*
X2371770Y43007D01*
X2371020Y45674D01*
X2370020Y47674D01*
X2368520Y49340D01*
X2366520Y50007D01*
G01X2386520Y30007D02*
Y50007D01*
X2383520Y46007D01*
G01Y30007D02*
X2389520D01*
G01X2401770Y46674D02*
X2403270Y48673D01*
X2405020Y49674D01*
X2407020Y50007D01*
X2409520Y49340D01*
X2411270Y47674D01*
X2411770Y45674D01*
X2411520Y43673D01*
X2410520Y42007D01*
X2405520Y38674D01*
X2403270Y36340D01*
X2401770Y33006D01*
X2401270Y30007D01*
X2411770D01*
G01X2423270Y36673D02*
X2429770D01*
G01X2446520Y30007D02*
Y50007D01*
X2443520Y46007D01*
G01Y30007D02*
X2449520D01*
G01X2466520Y50007D02*
X2464520Y49340D01*
X2463020Y47674D01*
X2462020Y45674D01*
X2461270Y43007D01*
X2461020Y40007D01*
X2461270Y37007D01*
X2462020Y34340D01*
X2463020Y32340D01*
X2464520Y30674D01*
X2466520Y30007D01*
X2468520Y30674D01*
X2470020Y32340D01*
X2471020Y34340D01*
X2471770Y37007D01*
X2472020Y40007D01*
X2471770Y43007D01*
X2471020Y45674D01*
X2470020Y47674D01*
X2468520Y49340D01*
X2466520Y50007D01*
G01X2483270Y36673D02*
X2489770D01*
G01X2506520Y30007D02*
Y50007D01*
X2503520Y46007D01*
G01Y30007D02*
X2509520D01*
G01X2521020Y33006D02*
X2522520Y31340D01*
X2524270Y30340D01*
X2526520Y30007D01*
X2528770Y30674D01*
X2530520Y32007D01*
X2531770Y34340D01*
X2532020Y37007D01*
X2531520Y39673D01*
X2530270Y41340D01*
X2528520Y42673D01*
X2526770Y43007D01*
X2525020Y42673D01*
X2522770Y41340D01*
X2523520Y50007D01*
X2530270D01*
G01X2354414Y78715D02*
Y98715D01*
X2351414Y94715D01*
G01Y78715D02*
X2357414D01*
G01X2374414Y78048D02*
X2373914Y78382D01*
Y79048D01*
X2374414Y79382D01*
X2374914Y79048D01*
Y78382D01*
X2374414Y78048D01*
G01X2389664Y87048D02*
X2391414Y89382D01*
X2392914Y90715D01*
X2394914Y91381D01*
X2396664Y90715D01*
X2397914Y89382D01*
X2398914Y87382D01*
X2399164Y85048D01*
X2398914Y83048D01*
X2397914Y81048D01*
X2396414Y79382D01*
X2394664Y78715D01*
X2392664Y79382D01*
X2390914Y81381D01*
X2389914Y84382D01*
X2389664Y87715D01*
X2390164Y92048D01*
X2390914Y94382D01*
X2392164Y96715D01*
X2393914Y98382D01*
X2395664Y98715D01*
X2397414Y98048D01*
X2398664Y96382D01*
G01X2426914Y78715D02*
Y92048D01*
G01Y88381D02*
X2427664Y90048D01*
X2428914Y91381D01*
X2430664Y92048D01*
X2432414Y91381D01*
X2433664Y90048D01*
X2434414Y88381D01*
Y78715D01*
G01Y88381D02*
X2435164Y90048D01*
X2436414Y91381D01*
X2438164Y92048D01*
X2439914Y91381D01*
X2441164Y90048D01*
X2441914Y88048D01*
Y78715D01*
G01X2446914D02*
Y92048D01*
G01Y88381D02*
X2447664Y90048D01*
X2448914Y91381D01*
X2450664Y92048D01*
X2452414Y91381D01*
X2453664Y90048D01*
X2454414Y88381D01*
Y78715D01*
G01Y88381D02*
X2455164Y90048D01*
X2456414Y91381D01*
X2458164Y92048D01*
X2459914Y91381D01*
X2461164Y90048D01*
X2461914Y88048D01*
Y78715D01*
G01X2434647Y-80235D02*
Y-68873D01*
X2432943Y-71145D01*
G01Y-80235D02*
X2436351D01*
G01X2447714D02*
Y-68873D01*
X2442459Y-77016D01*
X2449561D01*
G01X2434647Y2097521D02*
Y2108883D01*
X2432943Y2106611D01*
G01Y2097521D02*
X2436351D01*
G01X2447714D02*
Y2108883D01*
X2442459Y2100740D01*
X2449561D01*
G01X2499470Y-41200D02*
X2537075D01*
G01X2572413Y2112671D02*
Y-84022D01*
G01X2553476Y2093734D02*
Y-65085D01*
G01X2553477Y79600D02*
Y-65085D01*
G01X2537075Y-41200D02*
Y156118D01*
G01X2560388Y39447D02*
X2561099Y38311D01*
X2561951Y37554D01*
X2562945Y37175D01*
X2564081Y37554D01*
X2564933Y38311D01*
X2565786Y39447D01*
X2566070Y40962D01*
Y48537D01*
G01X2553476Y150797D02*
X2572413D01*
G01X2537075Y156118D02*
Y214489D01*
G01X2561525Y264419D02*
X2564933D01*
G01X2563229D02*
Y253057D01*
G01X2561525D02*
X2564933D01*
G01X2553476Y366679D02*
X2572413D01*
G01X2560246Y468749D02*
Y480111D01*
G01X2566212D02*
Y468749D01*
G01Y474430D02*
X2560246D01*
G01X2553476Y582561D02*
X2572413D01*
G01X2564081Y690312D02*
X2566922D01*
Y686903D01*
X2566070Y685767D01*
X2565075Y685010D01*
X2563655Y684631D01*
X2562235Y685010D01*
X2561241Y685767D01*
X2560388Y686903D01*
X2559820Y688229D01*
X2559536Y689744D01*
Y691069D01*
X2559820Y692205D01*
X2560388Y693531D01*
X2561241Y694667D01*
X2562093Y695425D01*
X2563229Y695993D01*
X2564223D01*
X2565359Y695614D01*
X2566212Y694857D01*
G01X2553476Y798443D02*
X2572413D01*
G01X2560151Y900703D02*
Y912065D01*
X2565549D01*
G01X2563560Y906573D02*
X2560151D01*
G01X2553476Y1014325D02*
X2572413D01*
G01X2566070Y1116774D02*
X2560388D01*
Y1128136D01*
X2566070D01*
G01X2563797Y1122644D02*
X2560388D01*
G01X2553476Y1230206D02*
X2572413D01*
G01X2560104Y1332466D02*
Y1343828D01*
X2562945D01*
X2564081Y1343260D01*
X2564933Y1342502D01*
X2565644Y1341366D01*
X2566212Y1340040D01*
X2566354Y1338147D01*
X2566212Y1336253D01*
X2565644Y1334928D01*
X2564933Y1333791D01*
X2564081Y1333034D01*
X2562945Y1332466D01*
X2560104D01*
G01X2553476Y1446088D02*
X2572413D01*
G01X2566354Y1558953D02*
X2565501Y1559521D01*
X2564507Y1559900D01*
X2563371D01*
X2562093Y1559332D01*
X2561099Y1558385D01*
X2560388Y1557249D01*
X2559820Y1555355D01*
X2559678Y1553651D01*
X2559962Y1551947D01*
X2560388Y1550810D01*
X2561241Y1549674D01*
X2562235Y1548917D01*
X2563229Y1548538D01*
X2564223D01*
X2565217Y1548917D01*
X2566070Y1549485D01*
X2566780Y1550242D01*
G01X2553476Y1661970D02*
X2572413D01*
G01X2564365Y1770290D02*
X2564933Y1770858D01*
X2565359Y1771804D01*
X2565644Y1773130D01*
X2565359Y1774266D01*
X2564791Y1775024D01*
X2563797Y1775592D01*
X2559962D01*
Y1764230D01*
X2564649D01*
X2565644Y1764987D01*
X2566212Y1766124D01*
X2566496Y1767449D01*
X2566212Y1768775D01*
X2565359Y1769911D01*
X2564365Y1770290D01*
X2559962D01*
G01X2553287Y1877852D02*
X2572224D01*
G01X2559678Y1980112D02*
X2563229Y1991474D01*
X2566780Y1980112D01*
G01X2565501Y1984089D02*
X2560956D01*
G01X2553476Y2093734D02*
Y1999246D01*
M02*
